G04 ================== begin FILE IDENTIFICATION RECORD ==================*
G04 Layout Name:  D:/<user>/Wistron_project/16318-2/gbr/16318-2.brd*
G04 Film Name:    DP_REF_L1*
G04 File Format:  Gerber RS274X*
G04 File Origin:  Cadence Allegro 16.5-S056*
G04 Origin Date:  Mon Aug 07 11:09:55 2017*
G04 *
G04 Layer:  BOARD GEOMETRY/DP_REF_L1_TBL*
G04 Layer:  BOARD GEOMETRY/DP_REF_L1_TOP*
G04 Layer:  BOARD GEOMETRY/PANEL_OUTLINE*
G04 *
G04 Offset:    (0.00 0.00)*
G04 Mirror:    No*
G04 Mode:      Positive*
G04 Rotation:  0*
G04 FullContactRelief:  No*
G04 UndefLineWidth:     6.00*
G04 ================== end FILE IDENTIFICATION RECORD ====================*
%FSLAX35Y35*MOIN*%
%IR0*IPPOS*OFA0.00000B0.00000*MIA0B0*SFA1.00000B1.00000*%
%ADD10C,.02*%
%ADD11C,.006*%
%ADD12C,.0049*%
%ADD13C,.00575*%
G75*
%LPD*%
G75*
G54D10*
G01X975497Y590830D02*
X1727997D01*
G01X975497Y556180D02*
X1727997D01*
G01X975497Y729430D02*
Y556180D01*
G01Y625480D02*
X1727997D01*
G01X975497Y694780D02*
X1727997D01*
G01X975497Y660130D02*
X1727997D01*
G01X975497Y729430D02*
X1727997D01*
G01X1150497D02*
Y556180D01*
G01X1412997Y729430D02*
Y556180D01*
G01X1517997Y729430D02*
Y556180D01*
G01X1727997Y729430D02*
Y556180D01*
G54D11*
G01X6250Y-32800D02*
Y-50300D01*
G01X1228Y-32800D02*
X11272D01*
G01X20038Y-50300D02*
Y-32800D01*
G01Y-41258D02*
X21130Y-39800D01*
X22222Y-38925D01*
X23968Y-38634D01*
X25278Y-38925D01*
X26807Y-40092D01*
X27462Y-41842D01*
Y-50300D01*
G01X41250Y-38634D02*
Y-50300D01*
G01Y-33967D02*
X40813Y-33675D01*
Y-33092D01*
X41250Y-32800D01*
X41687Y-33092D01*
Y-33675D01*
X41250Y-33967D01*
G01X55475Y-48259D02*
X56567Y-49425D01*
X58095Y-50300D01*
X59405D01*
X60715Y-49717D01*
X61588Y-48842D01*
X62025Y-47676D01*
X61807Y-45925D01*
X60933Y-45050D01*
X57003Y-43300D01*
X56130Y-41258D01*
X56567Y-39800D01*
X57440Y-38925D01*
X58750Y-38634D01*
X60060Y-38925D01*
X61370Y-39800D01*
G01X90693Y-54675D02*
X92222Y-55842D01*
X93968Y-56133D01*
X95496Y-55842D01*
X96807Y-54384D01*
X97680Y-52342D01*
Y-38634D01*
G01Y-40967D02*
X96807Y-39800D01*
X95496Y-38925D01*
X93968Y-38634D01*
X92222Y-39217D01*
X91130Y-40383D01*
X90256Y-42425D01*
X89820Y-44467D01*
X90038Y-46217D01*
X90912Y-48259D01*
X92222Y-49717D01*
X93968Y-50300D01*
X95278Y-50008D01*
X96807Y-48842D01*
X97680Y-47676D01*
G01X107975Y-42425D02*
X114962D01*
X114307Y-40383D01*
X113215Y-39217D01*
X111687Y-38634D01*
X110158Y-38925D01*
X108848Y-39800D01*
X107975Y-41842D01*
X107538Y-43592D01*
Y-45342D01*
X107975Y-47092D01*
X109067Y-48842D01*
X110377Y-50008D01*
X111905Y-50300D01*
X113433Y-49717D01*
X114962Y-47967D01*
G01X125693Y-50300D02*
Y-38634D01*
G01Y-40967D02*
X126785Y-39800D01*
X127877Y-38925D01*
X129405Y-38634D01*
X130496Y-38925D01*
X131807Y-39800D01*
G01X142320Y-50300D02*
Y-32800D01*
G01Y-41550D02*
X143412Y-39800D01*
X144722Y-38925D01*
X146032Y-38634D01*
X147996Y-39217D01*
X149307Y-40383D01*
X150180Y-42425D01*
Y-44758D01*
X149743Y-47092D01*
X148870Y-48842D01*
X147342Y-50008D01*
X146032Y-50300D01*
X144722Y-50008D01*
X143412Y-49134D01*
X142320Y-47676D01*
G01X160475Y-42425D02*
X167462D01*
X166807Y-40383D01*
X165715Y-39217D01*
X164187Y-38634D01*
X162658Y-38925D01*
X161348Y-39800D01*
X160475Y-41842D01*
X160038Y-43592D01*
Y-45342D01*
X160475Y-47092D01*
X161567Y-48842D01*
X162877Y-50008D01*
X164405Y-50300D01*
X165933Y-49717D01*
X167462Y-47967D01*
G01X178193Y-50300D02*
Y-38634D01*
G01Y-40967D02*
X179285Y-39800D01*
X180377Y-38925D01*
X181905Y-38634D01*
X182996Y-38925D01*
X184307Y-39800D01*
G01X216250Y-38634D02*
Y-50300D01*
G01Y-33967D02*
X215813Y-33675D01*
Y-33092D01*
X216250Y-32800D01*
X216687Y-33092D01*
Y-33675D01*
X216250Y-33967D01*
G01X230475Y-48259D02*
X231567Y-49425D01*
X233095Y-50300D01*
X234405D01*
X235715Y-49717D01*
X236588Y-48842D01*
X237025Y-47676D01*
X236807Y-45925D01*
X235933Y-45050D01*
X232003Y-43300D01*
X231130Y-41258D01*
X231567Y-39800D01*
X232440Y-38925D01*
X233750Y-38634D01*
X235060Y-38925D01*
X236370Y-39800D01*
G01X265256Y-54675D02*
X266785Y-55842D01*
X268095Y-56133D01*
X269842Y-55550D01*
X271152Y-54092D01*
X271807Y-51466D01*
Y-38634D01*
G01Y-33967D02*
X271370Y-33675D01*
Y-33092D01*
X271807Y-32800D01*
X272243Y-33092D01*
Y-33675D01*
X271807Y-33967D01*
G01X282538Y-38634D02*
Y-46800D01*
X283412Y-48842D01*
X284722Y-50008D01*
X286250Y-50300D01*
X287778Y-50008D01*
X289088Y-48842D01*
X289962Y-46800D01*
G01Y-50300D02*
Y-38634D01*
G01X300475Y-48259D02*
X301567Y-49425D01*
X303095Y-50300D01*
X304405D01*
X305715Y-49717D01*
X306588Y-48842D01*
X307025Y-47676D01*
X306807Y-45925D01*
X305933Y-45050D01*
X302003Y-43300D01*
X301130Y-41258D01*
X301567Y-39800D01*
X302440Y-38925D01*
X303750Y-38634D01*
X305060Y-38925D01*
X306370Y-39800D01*
G01X321250Y-32800D02*
Y-50300D01*
G01X318193Y-38634D02*
X324307D01*
G01X354940Y-50300D02*
Y-35425D01*
X355377Y-33967D01*
X356250Y-33092D01*
X357560Y-32800D01*
X358870Y-33383D01*
X359525Y-34842D01*
G01X356905Y-39800D02*
X352538D01*
G01X373750Y-50300D02*
X372440Y-50008D01*
X371130Y-48842D01*
X370256Y-46800D01*
X369820Y-44467D01*
X370256Y-42133D01*
X371130Y-40092D01*
X372440Y-38925D01*
X373750Y-38634D01*
X375060Y-38925D01*
X376370Y-40092D01*
X377243Y-42133D01*
X377462Y-44467D01*
X377243Y-46800D01*
X376370Y-48842D01*
X375060Y-50008D01*
X373750Y-50300D01*
G01X388193D02*
Y-38634D01*
G01Y-40967D02*
X389285Y-39800D01*
X390377Y-38925D01*
X391905Y-38634D01*
X392996Y-38925D01*
X394307Y-39800D01*
G01X421665Y-55550D02*
X422975Y-56133D01*
X424722Y-55550D01*
X425813Y-54384D01*
X426687Y-52925D01*
X427996Y-48259D01*
X430835Y-38634D01*
G01X423848D02*
X427996Y-48259D01*
G01X443750Y-50300D02*
X442440Y-50008D01*
X441130Y-48842D01*
X440256Y-46800D01*
X439820Y-44467D01*
X440256Y-42133D01*
X441130Y-40092D01*
X442440Y-38925D01*
X443750Y-38634D01*
X445060Y-38925D01*
X446370Y-40092D01*
X447243Y-42133D01*
X447462Y-44467D01*
X447243Y-46800D01*
X446370Y-48842D01*
X445060Y-50008D01*
X443750Y-50300D01*
G01X457538Y-38634D02*
Y-46800D01*
X458412Y-48842D01*
X459722Y-50008D01*
X461250Y-50300D01*
X462778Y-50008D01*
X464088Y-48842D01*
X464962Y-46800D01*
G01Y-50300D02*
Y-38634D01*
G01X475693Y-50300D02*
Y-38634D01*
G01Y-40967D02*
X476785Y-39800D01*
X477877Y-38925D01*
X479405Y-38634D01*
X480496Y-38925D01*
X481807Y-39800D01*
G01X510693Y-50300D02*
Y-38634D01*
G01Y-40967D02*
X511785Y-39800D01*
X512877Y-38925D01*
X514405Y-38634D01*
X515496Y-38925D01*
X516807Y-39800D01*
G01X527975Y-42425D02*
X534962D01*
X534307Y-40383D01*
X533215Y-39217D01*
X531687Y-38634D01*
X530158Y-38925D01*
X528848Y-39800D01*
X527975Y-41842D01*
X527538Y-43592D01*
Y-45342D01*
X527975Y-47092D01*
X529067Y-48842D01*
X530377Y-50008D01*
X531905Y-50300D01*
X533433Y-49717D01*
X534962Y-47967D01*
G01X547440Y-50300D02*
Y-35425D01*
X547877Y-33967D01*
X548750Y-33092D01*
X550060Y-32800D01*
X551370Y-33383D01*
X552025Y-34842D01*
G01X549405Y-39800D02*
X545038D01*
G01X562975Y-42425D02*
X569962D01*
X569307Y-40383D01*
X568215Y-39217D01*
X566687Y-38634D01*
X565158Y-38925D01*
X563848Y-39800D01*
X562975Y-41842D01*
X562538Y-43592D01*
Y-45342D01*
X562975Y-47092D01*
X564067Y-48842D01*
X565377Y-50008D01*
X566905Y-50300D01*
X568433Y-49717D01*
X569962Y-47967D01*
G01X580693Y-50300D02*
Y-38634D01*
G01Y-40967D02*
X581785Y-39800D01*
X582877Y-38925D01*
X584405Y-38634D01*
X585496Y-38925D01*
X586807Y-39800D01*
G01X597975Y-42425D02*
X604962D01*
X604307Y-40383D01*
X603215Y-39217D01*
X601687Y-38634D01*
X600158Y-38925D01*
X598848Y-39800D01*
X597975Y-41842D01*
X597538Y-43592D01*
Y-45342D01*
X597975Y-47092D01*
X599067Y-48842D01*
X600377Y-50008D01*
X601905Y-50300D01*
X603433Y-49717D01*
X604962Y-47967D01*
G01X615038Y-50300D02*
Y-38634D01*
G01Y-41550D02*
X615912Y-40092D01*
X617222Y-38925D01*
X618968Y-38634D01*
X620496Y-38925D01*
X621807Y-40092D01*
X622462Y-42133D01*
Y-50300D01*
G01X639743Y-40092D02*
X638215Y-38925D01*
X636905Y-38634D01*
X635158Y-39217D01*
X633848Y-40383D01*
X632975Y-42425D01*
X632756Y-44467D01*
X632975Y-46509D01*
X633848Y-48259D01*
X635158Y-49717D01*
X636905Y-50300D01*
X638433Y-49717D01*
X639743Y-48550D01*
G01X650475Y-42425D02*
X657462D01*
X656807Y-40383D01*
X655715Y-39217D01*
X654187Y-38634D01*
X652658Y-38925D01*
X651348Y-39800D01*
X650475Y-41842D01*
X650038Y-43592D01*
Y-45342D01*
X650475Y-47092D01*
X651567Y-48842D01*
X652877Y-50008D01*
X654405Y-50300D01*
X655933Y-49717D01*
X657462Y-47967D01*
G01X688750Y-32800D02*
Y-50300D01*
G01X685693Y-38634D02*
X691807D01*
G01X706250Y-50300D02*
X704940Y-50008D01*
X703630Y-48842D01*
X702756Y-46800D01*
X702320Y-44467D01*
X702756Y-42133D01*
X703630Y-40092D01*
X704940Y-38925D01*
X706250Y-38634D01*
X707560Y-38925D01*
X708870Y-40092D01*
X709743Y-42133D01*
X709962Y-44467D01*
X709743Y-46800D01*
X708870Y-48842D01*
X707560Y-50008D01*
X706250Y-50300D01*
G01X739940D02*
Y-35425D01*
X740377Y-33967D01*
X741250Y-33092D01*
X742560Y-32800D01*
X743870Y-33383D01*
X744525Y-34842D01*
G01X741905Y-39800D02*
X737538D01*
G01X758750Y-38634D02*
Y-50300D01*
G01Y-33967D02*
X758313Y-33675D01*
Y-33092D01*
X758750Y-32800D01*
X759187Y-33092D01*
Y-33675D01*
X758750Y-33967D01*
G01X772538Y-50300D02*
Y-38634D01*
G01Y-41550D02*
X773412Y-40092D01*
X774722Y-38925D01*
X776468Y-38634D01*
X777996Y-38925D01*
X779307Y-40092D01*
X779962Y-42133D01*
Y-50300D01*
G01X797680Y-32800D02*
Y-50300D01*
G01Y-47676D02*
X796807Y-49134D01*
X795496Y-50008D01*
X793968Y-50300D01*
X792222Y-49717D01*
X790912Y-48259D01*
X790038Y-46509D01*
X789820Y-44467D01*
X790038Y-42425D01*
X790912Y-40675D01*
X792222Y-39217D01*
X793968Y-38634D01*
X795496Y-38925D01*
X796588Y-39509D01*
X797680Y-40675D01*
G01X828750Y-32800D02*
Y-50300D01*
G01X825693Y-38634D02*
X831807D01*
G01X842538Y-50300D02*
Y-32800D01*
G01Y-41258D02*
X843630Y-39800D01*
X844722Y-38925D01*
X846468Y-38634D01*
X847778Y-38925D01*
X849307Y-40092D01*
X849962Y-41842D01*
Y-50300D01*
G01X860475Y-42425D02*
X867462D01*
X866807Y-40383D01*
X865715Y-39217D01*
X864187Y-38634D01*
X862658Y-38925D01*
X861348Y-39800D01*
X860475Y-41842D01*
X860038Y-43592D01*
Y-45342D01*
X860475Y-47092D01*
X861567Y-48842D01*
X862877Y-50008D01*
X864405Y-50300D01*
X865933Y-49717D01*
X867462Y-47967D01*
G01X893947Y-50300D02*
Y-32800D01*
X898313D01*
X900060Y-33675D01*
X901370Y-34842D01*
X902462Y-36591D01*
X903335Y-38634D01*
X903553Y-41550D01*
X903335Y-44467D01*
X902462Y-46509D01*
X901370Y-48259D01*
X900060Y-49425D01*
X898313Y-50300D01*
X893947D01*
G01X911883D02*
Y-32800D01*
X917123D01*
X918870Y-33675D01*
X920180Y-35717D01*
X920617Y-38050D01*
X920180Y-40383D01*
X919088Y-42133D01*
X917123Y-43009D01*
X911883D01*
G01X951250Y-38634D02*
Y-50300D01*
G01Y-33967D02*
X950813Y-33675D01*
Y-33092D01*
X951250Y-32800D01*
X951687Y-33092D01*
Y-33675D01*
X951250Y-33967D01*
G01X962200Y-50300D02*
Y-38634D01*
G01Y-41842D02*
X962855Y-40383D01*
X963947Y-39217D01*
X965475Y-38634D01*
X967003Y-39217D01*
X968095Y-40383D01*
X968750Y-41842D01*
Y-50300D01*
G01Y-41842D02*
X969405Y-40383D01*
X970496Y-39217D01*
X972025Y-38634D01*
X973553Y-39217D01*
X974645Y-40383D01*
X975300Y-42133D01*
Y-50300D01*
G01X982320Y-56133D02*
Y-38634D01*
G01Y-41258D02*
X983412Y-39800D01*
X984503Y-38925D01*
X986250Y-38634D01*
X987778Y-38925D01*
X989307Y-40383D01*
X989962Y-42425D01*
X990180Y-44467D01*
X989962Y-46509D01*
X989307Y-48550D01*
X987996Y-49717D01*
X986250Y-50300D01*
X984722Y-50008D01*
X983193Y-49134D01*
X982320Y-47967D01*
G01X1000475Y-42425D02*
X1007462D01*
X1006807Y-40383D01*
X1005715Y-39217D01*
X1004187Y-38634D01*
X1002658Y-38925D01*
X1001348Y-39800D01*
X1000475Y-41842D01*
X1000038Y-43592D01*
Y-45342D01*
X1000475Y-47092D01*
X1001567Y-48842D01*
X1002877Y-50008D01*
X1004405Y-50300D01*
X1005933Y-49717D01*
X1007462Y-47967D01*
G01X1025180Y-32800D02*
Y-50300D01*
G01Y-47676D02*
X1024307Y-49134D01*
X1022996Y-50008D01*
X1021468Y-50300D01*
X1019722Y-49717D01*
X1018412Y-48259D01*
X1017538Y-46509D01*
X1017320Y-44467D01*
X1017538Y-42425D01*
X1018412Y-40675D01*
X1019722Y-39217D01*
X1021468Y-38634D01*
X1022996Y-38925D01*
X1024088Y-39509D01*
X1025180Y-40675D01*
G01X1042680Y-50300D02*
Y-38634D01*
G01Y-40675D02*
X1041807Y-39509D01*
X1040496Y-38925D01*
X1038968Y-38634D01*
X1037440Y-39217D01*
X1036130Y-40383D01*
X1035256Y-42133D01*
X1034820Y-44467D01*
X1035256Y-46800D01*
X1036130Y-48550D01*
X1037440Y-49717D01*
X1038968Y-50300D01*
X1040496Y-50008D01*
X1041807Y-49134D01*
X1042680Y-47967D01*
G01X1052538Y-50300D02*
Y-38634D01*
G01Y-41550D02*
X1053412Y-40092D01*
X1054722Y-38925D01*
X1056468Y-38634D01*
X1057996Y-38925D01*
X1059307Y-40092D01*
X1059962Y-42133D01*
Y-50300D01*
G01X1077243Y-40092D02*
X1075715Y-38925D01*
X1074405Y-38634D01*
X1072658Y-39217D01*
X1071348Y-40383D01*
X1070475Y-42425D01*
X1070256Y-44467D01*
X1070475Y-46509D01*
X1071348Y-48259D01*
X1072658Y-49717D01*
X1074405Y-50300D01*
X1075933Y-49717D01*
X1077243Y-48550D01*
G01X1087975Y-42425D02*
X1094962D01*
X1094307Y-40383D01*
X1093215Y-39217D01*
X1091687Y-38634D01*
X1090158Y-38925D01*
X1088848Y-39800D01*
X1087975Y-41842D01*
X1087538Y-43592D01*
Y-45342D01*
X1087975Y-47092D01*
X1089067Y-48842D01*
X1090377Y-50008D01*
X1091905Y-50300D01*
X1093433Y-49717D01*
X1094962Y-47967D01*
G01X1126250Y-32800D02*
Y-50300D01*
G01X1123193Y-38634D02*
X1129307D01*
G01X1140693Y-50300D02*
Y-38634D01*
G01Y-40967D02*
X1141785Y-39800D01*
X1142877Y-38925D01*
X1144405Y-38634D01*
X1145496Y-38925D01*
X1146807Y-39800D01*
G01X1165180Y-50300D02*
Y-38634D01*
G01Y-40675D02*
X1164307Y-39509D01*
X1162996Y-38925D01*
X1161468Y-38634D01*
X1159940Y-39217D01*
X1158630Y-40383D01*
X1157756Y-42133D01*
X1157320Y-44467D01*
X1157756Y-46800D01*
X1158630Y-48550D01*
X1159940Y-49717D01*
X1161468Y-50300D01*
X1162996Y-50008D01*
X1164307Y-49134D01*
X1165180Y-47967D01*
G01X1182243Y-40092D02*
X1180715Y-38925D01*
X1179405Y-38634D01*
X1177658Y-39217D01*
X1176348Y-40383D01*
X1175475Y-42425D01*
X1175256Y-44467D01*
X1175475Y-46509D01*
X1176348Y-48259D01*
X1177658Y-49717D01*
X1179405Y-50300D01*
X1180933Y-49717D01*
X1182243Y-48550D01*
G01X1192975Y-42425D02*
X1199962D01*
X1199307Y-40383D01*
X1198215Y-39217D01*
X1196687Y-38634D01*
X1195158Y-38925D01*
X1193848Y-39800D01*
X1192975Y-41842D01*
X1192538Y-43592D01*
Y-45342D01*
X1192975Y-47092D01*
X1194067Y-48842D01*
X1195377Y-50008D01*
X1196905Y-50300D01*
X1198433Y-49717D01*
X1199962Y-47967D01*
G01X1210475Y-48259D02*
X1211567Y-49425D01*
X1213095Y-50300D01*
X1214405D01*
X1215715Y-49717D01*
X1216588Y-48842D01*
X1217025Y-47676D01*
X1216807Y-45925D01*
X1215933Y-45050D01*
X1212003Y-43300D01*
X1211130Y-41258D01*
X1211567Y-39800D01*
X1212440Y-38925D01*
X1213750Y-38634D01*
X1215060Y-38925D01*
X1216370Y-39800D01*
G01X1248750Y-38634D02*
Y-50300D01*
G01Y-33967D02*
X1248313Y-33675D01*
Y-33092D01*
X1248750Y-32800D01*
X1249187Y-33092D01*
Y-33675D01*
X1248750Y-33967D01*
G01X1262538Y-50300D02*
Y-38634D01*
G01Y-41550D02*
X1263412Y-40092D01*
X1264722Y-38925D01*
X1266468Y-38634D01*
X1267996Y-38925D01*
X1269307Y-40092D01*
X1269962Y-42133D01*
Y-50300D01*
G01X1301250D02*
Y-32800D01*
G01X1322680Y-50300D02*
Y-38634D01*
G01Y-40675D02*
X1321807Y-39509D01*
X1320496Y-38925D01*
X1318968Y-38634D01*
X1317440Y-39217D01*
X1316130Y-40383D01*
X1315256Y-42133D01*
X1314820Y-44467D01*
X1315256Y-46800D01*
X1316130Y-48550D01*
X1317440Y-49717D01*
X1318968Y-50300D01*
X1320496Y-50008D01*
X1321807Y-49134D01*
X1322680Y-47967D01*
G01X1331665Y-55550D02*
X1332975Y-56133D01*
X1334722Y-55550D01*
X1335813Y-54384D01*
X1336687Y-52925D01*
X1337996Y-48259D01*
X1340835Y-38634D01*
G01X1333848D02*
X1337996Y-48259D01*
G01X1350475Y-42425D02*
X1357462D01*
X1356807Y-40383D01*
X1355715Y-39217D01*
X1354187Y-38634D01*
X1352658Y-38925D01*
X1351348Y-39800D01*
X1350475Y-41842D01*
X1350038Y-43592D01*
Y-45342D01*
X1350475Y-47092D01*
X1351567Y-48842D01*
X1352877Y-50008D01*
X1354405Y-50300D01*
X1355933Y-49717D01*
X1357462Y-47967D01*
G01X1368193Y-50300D02*
Y-38634D01*
G01Y-40967D02*
X1369285Y-39800D01*
X1370377Y-38925D01*
X1371905Y-38634D01*
X1372996Y-38925D01*
X1374307Y-39800D01*
G01X1401883Y-32800D02*
Y-50300D01*
X1410617D01*
G01X1423750D02*
Y-32800D01*
X1421130Y-36300D01*
G01Y-50300D02*
X1426370D01*
G01X1441250Y-50883D02*
X1440813Y-50592D01*
Y-50008D01*
X1441250Y-49717D01*
X1441687Y-50008D01*
Y-50592D01*
X1441250Y-50883D01*
G01X999127Y722030D02*
X1004367D01*
G01X1001747D02*
Y704530D01*
G01X999127D02*
X1004367D01*
G01X1013570D02*
Y722030D01*
X1019247Y707447D01*
X1024924Y722030D01*
Y704530D01*
G01X1032380D02*
Y722030D01*
X1037620D01*
X1039367Y721155D01*
X1040677Y719113D01*
X1041114Y716780D01*
X1040677Y714447D01*
X1039585Y712697D01*
X1037620Y711821D01*
X1032380D01*
G01X1053155Y698697D02*
X1050972Y701613D01*
X1049880Y704530D01*
Y716196D01*
X1050972Y719113D01*
X1053155Y722030D01*
G01X1071747Y704530D02*
X1070000Y704822D01*
X1068472Y705988D01*
X1067162Y707738D01*
X1066288Y709780D01*
X1065852Y712113D01*
Y714447D01*
X1066288Y716780D01*
X1067162Y718822D01*
X1068472Y720571D01*
X1070000Y721738D01*
X1071747Y722030D01*
X1073493Y721738D01*
X1075022Y720571D01*
X1076332Y718822D01*
X1077206Y716780D01*
X1077642Y714447D01*
Y712113D01*
X1077206Y709780D01*
X1076332Y707738D01*
X1075022Y705988D01*
X1073493Y704822D01*
X1071747Y704530D01*
G01X1085535D02*
Y722030D01*
G01Y713572D02*
X1086627Y715030D01*
X1087719Y715905D01*
X1089465Y716196D01*
X1090775Y715905D01*
X1092304Y714738D01*
X1092959Y712988D01*
Y704530D01*
G01X1100197D02*
Y716196D01*
G01Y712988D02*
X1100852Y714447D01*
X1101944Y715613D01*
X1103472Y716196D01*
X1105000Y715613D01*
X1106092Y714447D01*
X1106747Y712988D01*
Y704530D01*
G01Y712988D02*
X1107402Y714447D01*
X1108493Y715613D01*
X1110022Y716196D01*
X1111550Y715613D01*
X1112642Y714447D01*
X1113297Y712697D01*
Y704530D01*
G01X1125339Y698697D02*
X1127522Y701613D01*
X1128614Y704530D01*
Y716196D01*
X1127522Y719113D01*
X1125339Y722030D01*
G01X977244Y739180D02*
Y756680D01*
X981610D01*
X983357Y755805D01*
X984667Y754638D01*
X985759Y752889D01*
X986632Y750846D01*
X986850Y747930D01*
X986632Y745013D01*
X985759Y742971D01*
X984667Y741221D01*
X983357Y740055D01*
X981610Y739180D01*
X977244D01*
G01X995180D02*
Y756680D01*
X1000420D01*
X1002167Y755805D01*
X1003477Y753763D01*
X1003914Y751430D01*
X1003477Y749097D01*
X1002385Y747347D01*
X1000420Y746471D01*
X995180D01*
G01X1031927Y756680D02*
X1037167D01*
G01X1034547D02*
Y739180D01*
G01X1031927D02*
X1037167D01*
G01X1046370D02*
Y756680D01*
X1052047Y742097D01*
X1057724Y756680D01*
Y739180D01*
G01X1065180D02*
Y756680D01*
X1070420D01*
X1072167Y755805D01*
X1073477Y753763D01*
X1073914Y751430D01*
X1073477Y749097D01*
X1072385Y747347D01*
X1070420Y746471D01*
X1065180D01*
G01X1091414Y739180D02*
X1082680D01*
Y756680D01*
X1091414D01*
G01X1087920Y748222D02*
X1082680D01*
G01X1099744Y739180D02*
Y756680D01*
X1104110D01*
X1105857Y755805D01*
X1107167Y754638D01*
X1108259Y752889D01*
X1109132Y750846D01*
X1109350Y747930D01*
X1109132Y745013D01*
X1108259Y742971D01*
X1107167Y741221D01*
X1105857Y740055D01*
X1104110Y739180D01*
X1099744D01*
G01X1116588D02*
X1122047Y756680D01*
X1127506Y739180D01*
G01X1125540Y745305D02*
X1118553D01*
G01X1134525Y739180D02*
Y756680D01*
X1144569Y739180D01*
Y756680D01*
G01X1161850Y755221D02*
X1160540Y756097D01*
X1159012Y756680D01*
X1157265D01*
X1155300Y755805D01*
X1153772Y754347D01*
X1152680Y752596D01*
X1151807Y749680D01*
X1151588Y747055D01*
X1152025Y744430D01*
X1152680Y742680D01*
X1153990Y740930D01*
X1155519Y739763D01*
X1157047Y739180D01*
X1158575D01*
X1160104Y739763D01*
X1161414Y740638D01*
X1162506Y741804D01*
G01X1178914Y739180D02*
X1170180D01*
Y756680D01*
X1178914D01*
G01X1175420Y748222D02*
X1170180D01*
G01X1209547Y756680D02*
Y739180D01*
G01X1204525Y756680D02*
X1214569D01*
G01X1221588Y739180D02*
X1227047Y756680D01*
X1232506Y739180D01*
G01X1230540Y745305D02*
X1223553D01*
G01X1246293Y748513D02*
X1247167Y749388D01*
X1247822Y750846D01*
X1248259Y752889D01*
X1247822Y754638D01*
X1246949Y755805D01*
X1245420Y756680D01*
X1239525D01*
Y739180D01*
X1246730D01*
X1248259Y740346D01*
X1249132Y742097D01*
X1249569Y744138D01*
X1249132Y746180D01*
X1247822Y747930D01*
X1246293Y748513D01*
X1239525D01*
G01X1257680Y756680D02*
Y739180D01*
X1266414D01*
G01X1283914D02*
X1275180D01*
Y756680D01*
X1283914D01*
G01X1280420Y748222D02*
X1275180D01*
G01X1297047Y738597D02*
X1296610Y738888D01*
Y739472D01*
X1297047Y739763D01*
X1297484Y739472D01*
Y738888D01*
X1297047Y738597D01*
G01Y746471D02*
X1296610Y746763D01*
Y747347D01*
X1297047Y747638D01*
X1297484Y747347D01*
Y746763D01*
X1297047Y746471D01*
G01X1327680Y756680D02*
Y739180D01*
X1336414D01*
G01X1349547D02*
Y756680D01*
X1346927Y753180D01*
G01Y739180D02*
X1352167D01*
G01X1027997Y565930D02*
Y583430D01*
X1025377Y579930D01*
G01Y565930D02*
X1030617D01*
G01X1045497Y583430D02*
X1043750Y582847D01*
X1042440Y581388D01*
X1041567Y579639D01*
X1040912Y577305D01*
X1040694Y574680D01*
X1040912Y572055D01*
X1041567Y569721D01*
X1042440Y567971D01*
X1043750Y566513D01*
X1045497Y565930D01*
X1047243Y566513D01*
X1048554Y567971D01*
X1049427Y569721D01*
X1050082Y572055D01*
X1050300Y574680D01*
X1050082Y577305D01*
X1049427Y579639D01*
X1048554Y581388D01*
X1047243Y582847D01*
X1045497Y583430D01*
G01X1062997D02*
X1061250Y582847D01*
X1059940Y581388D01*
X1059067Y579639D01*
X1058412Y577305D01*
X1058194Y574680D01*
X1058412Y572055D01*
X1059067Y569721D01*
X1059940Y567971D01*
X1061250Y566513D01*
X1062997Y565930D01*
X1064743Y566513D01*
X1066054Y567971D01*
X1066927Y569721D01*
X1067582Y572055D01*
X1067800Y574680D01*
X1067582Y577305D01*
X1066927Y579639D01*
X1066054Y581388D01*
X1064743Y582847D01*
X1062997Y583430D01*
G01X1080497Y565347D02*
X1080060Y565638D01*
Y566222D01*
X1080497Y566513D01*
X1080934Y566222D01*
Y565638D01*
X1080497Y565347D01*
G01X1097997Y583430D02*
X1096250Y582847D01*
X1094940Y581388D01*
X1094067Y579639D01*
X1093412Y577305D01*
X1093194Y574680D01*
X1093412Y572055D01*
X1094067Y569721D01*
X1094940Y567971D01*
X1096250Y566513D01*
X1097997Y565930D01*
X1099743Y566513D01*
X1101054Y567971D01*
X1101927Y569721D01*
X1102582Y572055D01*
X1102800Y574680D01*
X1102582Y577305D01*
X1101927Y579639D01*
X1101054Y581388D01*
X1099743Y582847D01*
X1097997Y583430D01*
G01X1023194Y634647D02*
X1032800Y647480D01*
G01X1027997Y649813D02*
Y632313D01*
G01X1032800Y634647D02*
X1023194Y647480D01*
G01X1021447Y641063D02*
X1034547D01*
G01X1041785Y637271D02*
X1043314Y635813D01*
X1045060Y635230D01*
X1046807Y635813D01*
X1048335Y637563D01*
X1049427Y640188D01*
X1049864Y642813D01*
Y646021D01*
X1049427Y648646D01*
X1048335Y650980D01*
X1047025Y652147D01*
X1045497Y652730D01*
X1043750Y652147D01*
X1042440Y650980D01*
X1041567Y649230D01*
X1041130Y646896D01*
X1041567Y644855D01*
X1042659Y642813D01*
X1043969Y641646D01*
X1045497Y641355D01*
X1047243Y641938D01*
X1048554Y643397D01*
X1049864Y646021D01*
G01X1058849Y649813D02*
X1060159Y651563D01*
X1061687Y652438D01*
X1063434Y652730D01*
X1065617Y652147D01*
X1067145Y650688D01*
X1067582Y648939D01*
X1067364Y647188D01*
X1066490Y645730D01*
X1062124Y642813D01*
X1060159Y640772D01*
X1058849Y637854D01*
X1058412Y635230D01*
X1067582D01*
G01X1080497Y634647D02*
X1080060Y634938D01*
Y635522D01*
X1080497Y635813D01*
X1080934Y635522D01*
Y634938D01*
X1080497Y634647D01*
G01X1097997Y652730D02*
X1096250Y652147D01*
X1094940Y650688D01*
X1094067Y648939D01*
X1093412Y646605D01*
X1093194Y643980D01*
X1093412Y641355D01*
X1094067Y639021D01*
X1094940Y637271D01*
X1096250Y635813D01*
X1097997Y635230D01*
X1099743Y635813D01*
X1101054Y637271D01*
X1101927Y639021D01*
X1102582Y641355D01*
X1102800Y643980D01*
X1102582Y646605D01*
X1101927Y648939D01*
X1101054Y650688D01*
X1099743Y652147D01*
X1097997Y652730D01*
G01X1023194Y599997D02*
X1032800Y612830D01*
G01X1027997Y615163D02*
Y597663D01*
G01X1032800Y599997D02*
X1023194Y612830D01*
G01X1021447Y606413D02*
X1034547D01*
G01X1041785Y602621D02*
X1043314Y601163D01*
X1045060Y600580D01*
X1046807Y601163D01*
X1048335Y602913D01*
X1049427Y605538D01*
X1049864Y608163D01*
Y611371D01*
X1049427Y613996D01*
X1048335Y616330D01*
X1047025Y617497D01*
X1045497Y618080D01*
X1043750Y617497D01*
X1042440Y616330D01*
X1041567Y614580D01*
X1041130Y612246D01*
X1041567Y610205D01*
X1042659Y608163D01*
X1043969Y606996D01*
X1045497Y606705D01*
X1047243Y607288D01*
X1048554Y608747D01*
X1049864Y611371D01*
G01X1062560Y600580D02*
X1062997Y604371D01*
X1063652Y607580D01*
X1064525Y610497D01*
X1065617Y613705D01*
X1067364Y618080D01*
X1058630D01*
G01X1080497Y599997D02*
X1080060Y600288D01*
Y600872D01*
X1080497Y601163D01*
X1080934Y600872D01*
Y600288D01*
X1080497Y599997D01*
G01X1097997Y618080D02*
X1096250Y617497D01*
X1094940Y616038D01*
X1094067Y614289D01*
X1093412Y611955D01*
X1093194Y609330D01*
X1093412Y606705D01*
X1094067Y604371D01*
X1094940Y602621D01*
X1096250Y601163D01*
X1097997Y600580D01*
X1099743Y601163D01*
X1101054Y602621D01*
X1101927Y604371D01*
X1102582Y606705D01*
X1102800Y609330D01*
X1102582Y611955D01*
X1101927Y614289D01*
X1101054Y616038D01*
X1099743Y617497D01*
X1097997Y618080D01*
G01X1036747Y669880D02*
X1038275Y670172D01*
X1040022Y671046D01*
X1041114Y672504D01*
X1041550Y674547D01*
X1041114Y676588D01*
X1039804Y678338D01*
X1037839Y679213D01*
X1035655D01*
X1034345Y679797D01*
X1033253Y681255D01*
X1032817Y683296D01*
X1033472Y685338D01*
X1035000Y686797D01*
X1036747Y687380D01*
X1038493Y686797D01*
X1040022Y685338D01*
X1040677Y683296D01*
X1040240Y681255D01*
X1039149Y679797D01*
X1037839Y679213D01*
X1035655D01*
X1033690Y678338D01*
X1032380Y676588D01*
X1031944Y674547D01*
X1032380Y672504D01*
X1033472Y671046D01*
X1035219Y670172D01*
X1036747Y669880D01*
G01X1049444Y672504D02*
X1050753Y671046D01*
X1052282Y670172D01*
X1054247Y669880D01*
X1056212Y670463D01*
X1057740Y671630D01*
X1058832Y673671D01*
X1059050Y676005D01*
X1058614Y678338D01*
X1057522Y679797D01*
X1055993Y680963D01*
X1054465Y681255D01*
X1052937Y680963D01*
X1050972Y679797D01*
X1051627Y687380D01*
X1057522D01*
G01X1071747Y669297D02*
X1071310Y669588D01*
Y670172D01*
X1071747Y670463D01*
X1072184Y670172D01*
Y669588D01*
X1071747Y669297D01*
G01X1089247Y687380D02*
X1087500Y686797D01*
X1086190Y685338D01*
X1085317Y683589D01*
X1084662Y681255D01*
X1084444Y678630D01*
X1084662Y676005D01*
X1085317Y673671D01*
X1086190Y671921D01*
X1087500Y670463D01*
X1089247Y669880D01*
X1090993Y670463D01*
X1092304Y671921D01*
X1093177Y673671D01*
X1093832Y676005D01*
X1094050Y678630D01*
X1093832Y681255D01*
X1093177Y683589D01*
X1092304Y685338D01*
X1090993Y686797D01*
X1089247Y687380D01*
G01X1187697Y722030D02*
X1190753Y704530D01*
X1194247Y722030D01*
X1197740Y704530D01*
X1200797Y722030D01*
G01X1209127D02*
X1214367D01*
G01X1211747D02*
Y704530D01*
G01X1209127D02*
X1214367D01*
G01X1224444D02*
Y722030D01*
X1228810D01*
X1230557Y721155D01*
X1231867Y719988D01*
X1232959Y718239D01*
X1233832Y716196D01*
X1234050Y713280D01*
X1233832Y710363D01*
X1232959Y708321D01*
X1231867Y706571D01*
X1230557Y705405D01*
X1228810Y704530D01*
X1224444D01*
G01X1246747Y722030D02*
Y704530D01*
G01X1241725Y722030D02*
X1251769D01*
G01X1259662Y704530D02*
Y722030D01*
G01X1268832D02*
Y704530D01*
G01Y713280D02*
X1259662D01*
G01X1280655Y698697D02*
X1278472Y701613D01*
X1277380Y704530D01*
Y716196D01*
X1278472Y719113D01*
X1280655Y722030D01*
G01X1292697Y704530D02*
Y716196D01*
G01Y712988D02*
X1293352Y714447D01*
X1294444Y715613D01*
X1295972Y716196D01*
X1297500Y715613D01*
X1298592Y714447D01*
X1299247Y712988D01*
Y704530D01*
G01Y712988D02*
X1299902Y714447D01*
X1300993Y715613D01*
X1302522Y716196D01*
X1304050Y715613D01*
X1305142Y714447D01*
X1305797Y712697D01*
Y704530D01*
G01X1316747Y716196D02*
Y704530D01*
G01Y720863D02*
X1316310Y721155D01*
Y721738D01*
X1316747Y722030D01*
X1317184Y721738D01*
Y721155D01*
X1316747Y720863D01*
G01X1334247Y704530D02*
Y722030D01*
G01X1348472Y706571D02*
X1349564Y705405D01*
X1351092Y704530D01*
X1352402D01*
X1353712Y705113D01*
X1354585Y705988D01*
X1355022Y707154D01*
X1354804Y708905D01*
X1353930Y709780D01*
X1350000Y711530D01*
X1349127Y713572D01*
X1349564Y715030D01*
X1350437Y715905D01*
X1351747Y716196D01*
X1353057Y715905D01*
X1354367Y715030D01*
G01X1370339Y698697D02*
X1372522Y701613D01*
X1373614Y704530D01*
Y716196D01*
X1372522Y719113D01*
X1370339Y722030D01*
G01X1223117Y565930D02*
Y583430D01*
X1215038Y570888D01*
X1225956D01*
G01X1237997Y565347D02*
X1237560Y565638D01*
Y566222D01*
X1237997Y566513D01*
X1238434Y566222D01*
Y565638D01*
X1237997Y565347D01*
G01X1251785Y567971D02*
X1253314Y566513D01*
X1255060Y565930D01*
X1256807Y566513D01*
X1258335Y568263D01*
X1259427Y570888D01*
X1259864Y573513D01*
Y576721D01*
X1259427Y579346D01*
X1258335Y581680D01*
X1257025Y582847D01*
X1255497Y583430D01*
X1253750Y582847D01*
X1252440Y581680D01*
X1251567Y579930D01*
X1251130Y577596D01*
X1251567Y575555D01*
X1252659Y573513D01*
X1253969Y572346D01*
X1255497Y572055D01*
X1257243Y572638D01*
X1258554Y574097D01*
X1259864Y576721D01*
G01X1269067Y565347D02*
X1276927Y583430D01*
G01X1290497Y565930D02*
Y583430D01*
X1287877Y579930D01*
G01Y565930D02*
X1293117D01*
G01X1307997D02*
Y583430D01*
X1305377Y579930D01*
G01Y565930D02*
X1310617D01*
G01X1325497Y565347D02*
X1325060Y565638D01*
Y566222D01*
X1325497Y566513D01*
X1325934Y566222D01*
Y565638D01*
X1325497Y565347D01*
G01X1342997Y565930D02*
Y583430D01*
X1340377Y579930D01*
G01Y565930D02*
X1345617D01*
G01X1215694Y638730D02*
X1217003Y636688D01*
X1218750Y635522D01*
X1220715Y635230D01*
X1222462Y635522D01*
X1224209Y636980D01*
X1225300Y638730D01*
X1225519Y640480D01*
X1225082Y642521D01*
X1223554Y643980D01*
X1222025Y644563D01*
X1220060D01*
G01X1222025D02*
X1223335Y645438D01*
X1224427Y646896D01*
X1224864Y648646D01*
X1224427Y650397D01*
X1223335Y651855D01*
X1221370Y652730D01*
X1219405Y652438D01*
X1217440Y651271D01*
G01X1237997Y634647D02*
X1237560Y634938D01*
Y635522D01*
X1237997Y635813D01*
X1238434Y635522D01*
Y634938D01*
X1237997Y634647D01*
G01X1255060Y635230D02*
X1255497Y639021D01*
X1256152Y642230D01*
X1257025Y645147D01*
X1258117Y648355D01*
X1259864Y652730D01*
X1251130D01*
G01X1268194Y637854D02*
X1269503Y636396D01*
X1271032Y635522D01*
X1272997Y635230D01*
X1274962Y635813D01*
X1276490Y636980D01*
X1277582Y639021D01*
X1277800Y641355D01*
X1277364Y643688D01*
X1276272Y645147D01*
X1274743Y646313D01*
X1273215Y646605D01*
X1271687Y646313D01*
X1269722Y645147D01*
X1270377Y652730D01*
X1276272D01*
G01X1286567Y634647D02*
X1294427Y652730D01*
G01X1303194Y638730D02*
X1304503Y636688D01*
X1306250Y635522D01*
X1308215Y635230D01*
X1309962Y635522D01*
X1311709Y636980D01*
X1312800Y638730D01*
X1313019Y640480D01*
X1312582Y642521D01*
X1311054Y643980D01*
X1309525Y644563D01*
X1307560D01*
G01X1309525D02*
X1310835Y645438D01*
X1311927Y646896D01*
X1312364Y648646D01*
X1311927Y650397D01*
X1310835Y651855D01*
X1308870Y652730D01*
X1306905Y652438D01*
X1304940Y651271D01*
G01X1325497Y634647D02*
X1325060Y634938D01*
Y635522D01*
X1325497Y635813D01*
X1325934Y635522D01*
Y634938D01*
X1325497Y634647D01*
G01X1338194Y637854D02*
X1339503Y636396D01*
X1341032Y635522D01*
X1342997Y635230D01*
X1344962Y635813D01*
X1346490Y636980D01*
X1347582Y639021D01*
X1347800Y641355D01*
X1347364Y643688D01*
X1346272Y645147D01*
X1344743Y646313D01*
X1343215Y646605D01*
X1341687Y646313D01*
X1339722Y645147D01*
X1340377Y652730D01*
X1346272D01*
G01X1224444Y604080D02*
X1225753Y602038D01*
X1227500Y600872D01*
X1229465Y600580D01*
X1231212Y600872D01*
X1232959Y602330D01*
X1234050Y604080D01*
X1234269Y605830D01*
X1233832Y607871D01*
X1232304Y609330D01*
X1230775Y609913D01*
X1228810D01*
G01X1230775D02*
X1232085Y610788D01*
X1233177Y612246D01*
X1233614Y613996D01*
X1233177Y615747D01*
X1232085Y617205D01*
X1230120Y618080D01*
X1228155Y617788D01*
X1226190Y616621D01*
G01X1246747Y599997D02*
X1246310Y600288D01*
Y600872D01*
X1246747Y601163D01*
X1247184Y600872D01*
Y600288D01*
X1246747Y599997D01*
G01X1259444Y603204D02*
X1260753Y601746D01*
X1262282Y600872D01*
X1264247Y600580D01*
X1266212Y601163D01*
X1267740Y602330D01*
X1268832Y604371D01*
X1269050Y606705D01*
X1268614Y609038D01*
X1267522Y610497D01*
X1265993Y611663D01*
X1264465Y611955D01*
X1262937Y611663D01*
X1260972Y610497D01*
X1261627Y618080D01*
X1267522D01*
G01X1277817Y599997D02*
X1285677Y618080D01*
G01X1301867Y600580D02*
Y618080D01*
X1293788Y605538D01*
X1304706D01*
G01X1316747Y599997D02*
X1316310Y600288D01*
Y600872D01*
X1316747Y601163D01*
X1317184Y600872D01*
Y600288D01*
X1316747Y599997D01*
G01X1334247Y618080D02*
X1332500Y617497D01*
X1331190Y616038D01*
X1330317Y614289D01*
X1329662Y611955D01*
X1329444Y609330D01*
X1329662Y606705D01*
X1330317Y604371D01*
X1331190Y602621D01*
X1332500Y601163D01*
X1334247Y600580D01*
X1335993Y601163D01*
X1337304Y602621D01*
X1338177Y604371D01*
X1338832Y606705D01*
X1339050Y609330D01*
X1338832Y611955D01*
X1338177Y614289D01*
X1337304Y616038D01*
X1335993Y617497D01*
X1334247Y618080D01*
G01X1215694Y672504D02*
X1217003Y671046D01*
X1218532Y670172D01*
X1220497Y669880D01*
X1222462Y670463D01*
X1223990Y671630D01*
X1225082Y673671D01*
X1225300Y676005D01*
X1224864Y678338D01*
X1223772Y679797D01*
X1222243Y680963D01*
X1220715Y681255D01*
X1219187Y680963D01*
X1217222Y679797D01*
X1217877Y687380D01*
X1223772D01*
G01X1237997Y669297D02*
X1237560Y669588D01*
Y670172D01*
X1237997Y670463D01*
X1238434Y670172D01*
Y669588D01*
X1237997Y669297D01*
G01X1255060Y669880D02*
X1255497Y673671D01*
X1256152Y676880D01*
X1257025Y679797D01*
X1258117Y683005D01*
X1259864Y687380D01*
X1251130D01*
G01X1268194Y672504D02*
X1269503Y671046D01*
X1271032Y670172D01*
X1272997Y669880D01*
X1274962Y670463D01*
X1276490Y671630D01*
X1277582Y673671D01*
X1277800Y676005D01*
X1277364Y678338D01*
X1276272Y679797D01*
X1274743Y680963D01*
X1273215Y681255D01*
X1271687Y680963D01*
X1269722Y679797D01*
X1270377Y687380D01*
X1276272D01*
G01X1286567Y669297D02*
X1294427Y687380D01*
G01X1303849Y677171D02*
X1305377Y679213D01*
X1306687Y680380D01*
X1308434Y680963D01*
X1309962Y680380D01*
X1311054Y679213D01*
X1311927Y677463D01*
X1312145Y675422D01*
X1311927Y673671D01*
X1311054Y671921D01*
X1309743Y670463D01*
X1308215Y669880D01*
X1306469Y670463D01*
X1304940Y672213D01*
X1304067Y674838D01*
X1303849Y677755D01*
X1304285Y681546D01*
X1304940Y683589D01*
X1306032Y685630D01*
X1307560Y687088D01*
X1309089Y687380D01*
X1310617Y686797D01*
X1311709Y685338D01*
G01X1325497Y669297D02*
X1325060Y669588D01*
Y670172D01*
X1325497Y670463D01*
X1325934Y670172D01*
Y669588D01*
X1325497Y669297D01*
G01X1338194Y672504D02*
X1339503Y671046D01*
X1341032Y670172D01*
X1342997Y669880D01*
X1344962Y670463D01*
X1346490Y671630D01*
X1347582Y673671D01*
X1347800Y676005D01*
X1347364Y678338D01*
X1346272Y679797D01*
X1344743Y680963D01*
X1343215Y681255D01*
X1341687Y680963D01*
X1339722Y679797D01*
X1340377Y687380D01*
X1346272D01*
G01X1451944Y565930D02*
Y583430D01*
X1456310D01*
X1458057Y582555D01*
X1459367Y581388D01*
X1460459Y579639D01*
X1461332Y577596D01*
X1461550Y574680D01*
X1461332Y571763D01*
X1460459Y569721D01*
X1459367Y567971D01*
X1458057Y566805D01*
X1456310Y565930D01*
X1451944D01*
G01X1469880D02*
Y583430D01*
X1475120D01*
X1476867Y582555D01*
X1478177Y580513D01*
X1478614Y578180D01*
X1478177Y575847D01*
X1477085Y574097D01*
X1475120Y573221D01*
X1469880D01*
G01X1451944Y635230D02*
Y652730D01*
X1456310D01*
X1458057Y651855D01*
X1459367Y650688D01*
X1460459Y648939D01*
X1461332Y646896D01*
X1461550Y643980D01*
X1461332Y641063D01*
X1460459Y639021D01*
X1459367Y637271D01*
X1458057Y636105D01*
X1456310Y635230D01*
X1451944D01*
G01X1469880D02*
Y652730D01*
X1475120D01*
X1476867Y651855D01*
X1478177Y649813D01*
X1478614Y647480D01*
X1478177Y645147D01*
X1477085Y643397D01*
X1475120Y642521D01*
X1469880D01*
G01X1451944Y600580D02*
Y618080D01*
X1456310D01*
X1458057Y617205D01*
X1459367Y616038D01*
X1460459Y614289D01*
X1461332Y612246D01*
X1461550Y609330D01*
X1461332Y606413D01*
X1460459Y604371D01*
X1459367Y602621D01*
X1458057Y601455D01*
X1456310Y600580D01*
X1451944D01*
G01X1469880D02*
Y618080D01*
X1475120D01*
X1476867Y617205D01*
X1478177Y615163D01*
X1478614Y612830D01*
X1478177Y610497D01*
X1477085Y608747D01*
X1475120Y607871D01*
X1469880D01*
G01X1439247Y722030D02*
Y704530D01*
G01X1434225Y722030D02*
X1444269D01*
G01X1456747Y704530D02*
Y712405D01*
X1452380Y722030D01*
G01X1461114D02*
X1456747Y712405D01*
G01X1469880Y704530D02*
Y722030D01*
X1475120D01*
X1476867Y721155D01*
X1478177Y719113D01*
X1478614Y716780D01*
X1478177Y714447D01*
X1477085Y712697D01*
X1475120Y711821D01*
X1469880D01*
G01X1496114Y704530D02*
X1487380D01*
Y722030D01*
X1496114D01*
G01X1492620Y713572D02*
X1487380D01*
G01X1451944Y669880D02*
Y687380D01*
X1456310D01*
X1458057Y686505D01*
X1459367Y685338D01*
X1460459Y683589D01*
X1461332Y681546D01*
X1461550Y678630D01*
X1461332Y675713D01*
X1460459Y673671D01*
X1459367Y671921D01*
X1458057Y670755D01*
X1456310Y669880D01*
X1451944D01*
G01X1469880D02*
Y687380D01*
X1475120D01*
X1476867Y686505D01*
X1478177Y684463D01*
X1478614Y682130D01*
X1478177Y679797D01*
X1477085Y678047D01*
X1475120Y677171D01*
X1469880D01*
G01X1539880Y704530D02*
Y722030D01*
X1545339D01*
X1547085Y721155D01*
X1548177Y719988D01*
X1548614Y717655D01*
X1548177Y715321D01*
X1546867Y713863D01*
X1545339Y712988D01*
X1539880D01*
G01X1545339D02*
X1548614Y704530D01*
G01X1558472Y712405D02*
X1565459D01*
X1564804Y714447D01*
X1563712Y715613D01*
X1562184Y716196D01*
X1560655Y715905D01*
X1559345Y715030D01*
X1558472Y712988D01*
X1558035Y711238D01*
Y709488D01*
X1558472Y707738D01*
X1559564Y705988D01*
X1560874Y704822D01*
X1562402Y704530D01*
X1563930Y705113D01*
X1565459Y706863D01*
G01X1577937Y704530D02*
Y719405D01*
X1578374Y720863D01*
X1579247Y721738D01*
X1580557Y722030D01*
X1581867Y721447D01*
X1582522Y719988D01*
G01X1579902Y715030D02*
X1575535D01*
G01X1596747Y703947D02*
X1596310Y704238D01*
Y704822D01*
X1596747Y705113D01*
X1597184Y704822D01*
Y704238D01*
X1596747Y703947D01*
G01X1627380Y704530D02*
Y722030D01*
X1632620D01*
X1634367Y721155D01*
X1635677Y719113D01*
X1636114Y716780D01*
X1635677Y714447D01*
X1634585Y712697D01*
X1632620Y711821D01*
X1627380D01*
G01X1649247Y704530D02*
Y722030D01*
G01X1670677Y704530D02*
Y716196D01*
G01Y714155D02*
X1669804Y715321D01*
X1668493Y715905D01*
X1666965Y716196D01*
X1665437Y715613D01*
X1664127Y714447D01*
X1663253Y712697D01*
X1662817Y710363D01*
X1663253Y708030D01*
X1664127Y706280D01*
X1665437Y705113D01*
X1666965Y704530D01*
X1668493Y704822D01*
X1669804Y705696D01*
X1670677Y706863D01*
G01X1680535Y704530D02*
Y716196D01*
G01Y713280D02*
X1681409Y714738D01*
X1682719Y715905D01*
X1684465Y716196D01*
X1685993Y715905D01*
X1687304Y714738D01*
X1687959Y712697D01*
Y704530D01*
G01X1698472Y712405D02*
X1705459D01*
X1704804Y714447D01*
X1703712Y715613D01*
X1702184Y716196D01*
X1700655Y715905D01*
X1699345Y715030D01*
X1698472Y712988D01*
X1698035Y711238D01*
Y709488D01*
X1698472Y707738D01*
X1699564Y705988D01*
X1700874Y704822D01*
X1702402Y704530D01*
X1703930Y705113D01*
X1705459Y706863D01*
G01X1609880Y583430D02*
Y565930D01*
X1618614D01*
G01X1627599Y580513D02*
X1628909Y582263D01*
X1630437Y583138D01*
X1632184Y583430D01*
X1634367Y582847D01*
X1635895Y581388D01*
X1636332Y579639D01*
X1636114Y577888D01*
X1635240Y576430D01*
X1630874Y573513D01*
X1628909Y571472D01*
X1627599Y568554D01*
X1627162Y565930D01*
X1636332D01*
G01X1609880Y652730D02*
Y635230D01*
X1618614D01*
G01X1627599Y649813D02*
X1628909Y651563D01*
X1630437Y652438D01*
X1632184Y652730D01*
X1634367Y652147D01*
X1635895Y650688D01*
X1636332Y648939D01*
X1636114Y647188D01*
X1635240Y645730D01*
X1630874Y642813D01*
X1628909Y640772D01*
X1627599Y637854D01*
X1627162Y635230D01*
X1636332D01*
G01X1609880Y618080D02*
Y600580D01*
X1618614D01*
G01X1627599Y615163D02*
X1628909Y616913D01*
X1630437Y617788D01*
X1632184Y618080D01*
X1634367Y617497D01*
X1635895Y616038D01*
X1636332Y614289D01*
X1636114Y612538D01*
X1635240Y611080D01*
X1630874Y608163D01*
X1628909Y606122D01*
X1627599Y603204D01*
X1627162Y600580D01*
X1636332D01*
G01X1609880Y687380D02*
Y669880D01*
X1618614D01*
G01X1627599Y684463D02*
X1628909Y686213D01*
X1630437Y687088D01*
X1632184Y687380D01*
X1634367Y686797D01*
X1635895Y685338D01*
X1636332Y683589D01*
X1636114Y681838D01*
X1635240Y680380D01*
X1630874Y677463D01*
X1628909Y675422D01*
X1627599Y672504D01*
X1627162Y669880D01*
X1636332D01*
G01X1744744Y703947D02*
X1754350Y716780D01*
G01X1749547Y719113D02*
Y701613D01*
G01X1754350Y703947D02*
X1744744Y716780D01*
G01X1742997Y710363D02*
X1756097D01*
G01X1781709D02*
X1787385D01*
G01X1814744Y704530D02*
Y722030D01*
X1819110D01*
X1820857Y721155D01*
X1822167Y719988D01*
X1823259Y718239D01*
X1824132Y716196D01*
X1824350Y713280D01*
X1824132Y710363D01*
X1823259Y708321D01*
X1822167Y706571D01*
X1820857Y705405D01*
X1819110Y704530D01*
X1814744D01*
G01X1833772Y712405D02*
X1840759D01*
X1840104Y714447D01*
X1839012Y715613D01*
X1837484Y716196D01*
X1835955Y715905D01*
X1834645Y715030D01*
X1833772Y712988D01*
X1833335Y711238D01*
Y709488D01*
X1833772Y707738D01*
X1834864Y705988D01*
X1836174Y704822D01*
X1837702Y704530D01*
X1839230Y705113D01*
X1840759Y706863D01*
G01X1850835Y704530D02*
Y716196D01*
G01Y713280D02*
X1851709Y714738D01*
X1853019Y715905D01*
X1854765Y716196D01*
X1856293Y715905D01*
X1857604Y714738D01*
X1858259Y712697D01*
Y704530D01*
G01X1872047D02*
X1870737Y704822D01*
X1869427Y705988D01*
X1868553Y708030D01*
X1868117Y710363D01*
X1868553Y712697D01*
X1869427Y714738D01*
X1870737Y715905D01*
X1872047Y716196D01*
X1873357Y715905D01*
X1874667Y714738D01*
X1875540Y712697D01*
X1875759Y710363D01*
X1875540Y708030D01*
X1874667Y705988D01*
X1873357Y704822D01*
X1872047Y704530D01*
G01X1889547Y722030D02*
Y704530D01*
G01X1886490Y716196D02*
X1892604D01*
G01X1903772Y712405D02*
X1910759D01*
X1910104Y714447D01*
X1909012Y715613D01*
X1907484Y716196D01*
X1905955Y715905D01*
X1904645Y715030D01*
X1903772Y712988D01*
X1903335Y711238D01*
Y709488D01*
X1903772Y707738D01*
X1904864Y705988D01*
X1906174Y704822D01*
X1907702Y704530D01*
X1909230Y705113D01*
X1910759Y706863D01*
G01X1921272Y706571D02*
X1922364Y705405D01*
X1923892Y704530D01*
X1925202D01*
X1926512Y705113D01*
X1927385Y705988D01*
X1927822Y707154D01*
X1927604Y708905D01*
X1926730Y709780D01*
X1922800Y711530D01*
X1921927Y713572D01*
X1922364Y715030D01*
X1923237Y715905D01*
X1924547Y716196D01*
X1925857Y715905D01*
X1927167Y715030D01*
G01X1959547Y722030D02*
Y704530D01*
G01X1956490Y716196D02*
X1962604D01*
G01X1973335Y704530D02*
Y722030D01*
G01Y713572D02*
X1974427Y715030D01*
X1975519Y715905D01*
X1977265Y716196D01*
X1978575Y715905D01*
X1980104Y714738D01*
X1980759Y712988D01*
Y704530D01*
G01X1998477D02*
Y716196D01*
G01Y714155D02*
X1997604Y715321D01*
X1996293Y715905D01*
X1994765Y716196D01*
X1993237Y715613D01*
X1991927Y714447D01*
X1991053Y712697D01*
X1990617Y710363D01*
X1991053Y708030D01*
X1991927Y706280D01*
X1993237Y705113D01*
X1994765Y704530D01*
X1996293Y704822D01*
X1997604Y705696D01*
X1998477Y706863D01*
G01X2012047Y722030D02*
Y704530D01*
G01X2008990Y716196D02*
X2015104D01*
G01X2047047Y722030D02*
Y704530D01*
G01X2043990Y716196D02*
X2050104D01*
G01X2060835Y704530D02*
Y722030D01*
G01Y713572D02*
X2061927Y715030D01*
X2063019Y715905D01*
X2064765Y716196D01*
X2066075Y715905D01*
X2067604Y714738D01*
X2068259Y712988D01*
Y704530D01*
G01X2082047Y716196D02*
Y704530D01*
G01Y720863D02*
X2081610Y721155D01*
Y721738D01*
X2082047Y722030D01*
X2082484Y721738D01*
Y721155D01*
X2082047Y720863D01*
G01X2096272Y706571D02*
X2097364Y705405D01*
X2098892Y704530D01*
X2100202D01*
X2101512Y705113D01*
X2102385Y705988D01*
X2102822Y707154D01*
X2102604Y708905D01*
X2101730Y709780D01*
X2097800Y711530D01*
X2096927Y713572D01*
X2097364Y715030D01*
X2098237Y715905D01*
X2099547Y716196D01*
X2100857Y715905D01*
X2102167Y715030D01*
G01X2131927Y722030D02*
X2137167D01*
G01X2134547D02*
Y704530D01*
G01X2131927D02*
X2137167D01*
G01X2145497D02*
Y716196D01*
G01Y712988D02*
X2146152Y714447D01*
X2147244Y715613D01*
X2148772Y716196D01*
X2150300Y715613D01*
X2151392Y714447D01*
X2152047Y712988D01*
Y704530D01*
G01Y712988D02*
X2152702Y714447D01*
X2153793Y715613D01*
X2155322Y716196D01*
X2156850Y715613D01*
X2157942Y714447D01*
X2158597Y712697D01*
Y704530D01*
G01X2165617Y698697D02*
Y716196D01*
G01Y713572D02*
X2166709Y715030D01*
X2167800Y715905D01*
X2169547Y716196D01*
X2171075Y715905D01*
X2172604Y714447D01*
X2173259Y712405D01*
X2173477Y710363D01*
X2173259Y708321D01*
X2172604Y706280D01*
X2171293Y705113D01*
X2169547Y704530D01*
X2168019Y704822D01*
X2166490Y705696D01*
X2165617Y706863D01*
G01X2183772Y712405D02*
X2190759D01*
X2190104Y714447D01*
X2189012Y715613D01*
X2187484Y716196D01*
X2185955Y715905D01*
X2184645Y715030D01*
X2183772Y712988D01*
X2183335Y711238D01*
Y709488D01*
X2183772Y707738D01*
X2184864Y705988D01*
X2186174Y704822D01*
X2187702Y704530D01*
X2189230Y705113D01*
X2190759Y706863D01*
G01X2208477Y722030D02*
Y704530D01*
G01Y707154D02*
X2207604Y705696D01*
X2206293Y704822D01*
X2204765Y704530D01*
X2203019Y705113D01*
X2201709Y706571D01*
X2200835Y708321D01*
X2200617Y710363D01*
X2200835Y712405D01*
X2201709Y714155D01*
X2203019Y715613D01*
X2204765Y716196D01*
X2206293Y715905D01*
X2207385Y715321D01*
X2208477Y714155D01*
G01X2225977Y704530D02*
Y716196D01*
G01Y714155D02*
X2225104Y715321D01*
X2223793Y715905D01*
X2222265Y716196D01*
X2220737Y715613D01*
X2219427Y714447D01*
X2218553Y712697D01*
X2218117Y710363D01*
X2218553Y708030D01*
X2219427Y706280D01*
X2220737Y705113D01*
X2222265Y704530D01*
X2223793Y704822D01*
X2225104Y705696D01*
X2225977Y706863D01*
G01X2235835Y704530D02*
Y716196D01*
G01Y713280D02*
X2236709Y714738D01*
X2238019Y715905D01*
X2239765Y716196D01*
X2241293Y715905D01*
X2242604Y714738D01*
X2243259Y712697D01*
Y704530D01*
G01X2260540Y714738D02*
X2259012Y715905D01*
X2257702Y716196D01*
X2255955Y715613D01*
X2254645Y714447D01*
X2253772Y712405D01*
X2253553Y710363D01*
X2253772Y708321D01*
X2254645Y706571D01*
X2255955Y705113D01*
X2257702Y704530D01*
X2259230Y705113D01*
X2260540Y706280D01*
G01X2271272Y712405D02*
X2278259D01*
X2277604Y714447D01*
X2276512Y715613D01*
X2274984Y716196D01*
X2273455Y715905D01*
X2272145Y715030D01*
X2271272Y712988D01*
X2270835Y711238D01*
Y709488D01*
X2271272Y707738D01*
X2272364Y705988D01*
X2273674Y704822D01*
X2275202Y704530D01*
X2276730Y705113D01*
X2278259Y706863D01*
G01X1819547Y681546D02*
Y669880D01*
G01Y686213D02*
X1819110Y686505D01*
Y687088D01*
X1819547Y687380D01*
X1819984Y687088D01*
Y686505D01*
X1819547Y686213D01*
G01X1833772Y671921D02*
X1834864Y670755D01*
X1836392Y669880D01*
X1837702D01*
X1839012Y670463D01*
X1839885Y671338D01*
X1840322Y672504D01*
X1840104Y674255D01*
X1839230Y675130D01*
X1835300Y676880D01*
X1834427Y678922D01*
X1834864Y680380D01*
X1835737Y681255D01*
X1837047Y681546D01*
X1838357Y681255D01*
X1839667Y680380D01*
G01X1867025Y669880D02*
Y687380D01*
X1877069Y669880D01*
Y687380D01*
G01X1889547Y669880D02*
X1887800Y670172D01*
X1886272Y671338D01*
X1884962Y673088D01*
X1884088Y675130D01*
X1883652Y677463D01*
Y679797D01*
X1884088Y682130D01*
X1884962Y684172D01*
X1886272Y685921D01*
X1887800Y687088D01*
X1889547Y687380D01*
X1891293Y687088D01*
X1892822Y685921D01*
X1894132Y684172D01*
X1895006Y682130D01*
X1895442Y679797D01*
Y677463D01*
X1895006Y675130D01*
X1894132Y673088D01*
X1892822Y671338D01*
X1891293Y670172D01*
X1889547Y669880D01*
G01X1907047Y687380D02*
Y669880D01*
G01X1902025Y687380D02*
X1912069D01*
G01X1938335Y681546D02*
Y673380D01*
X1939209Y671338D01*
X1940519Y670172D01*
X1942047Y669880D01*
X1943575Y670172D01*
X1944885Y671338D01*
X1945759Y673380D01*
G01Y669880D02*
Y681546D01*
G01X1956272Y671921D02*
X1957364Y670755D01*
X1958892Y669880D01*
X1960202D01*
X1961512Y670463D01*
X1962385Y671338D01*
X1962822Y672504D01*
X1962604Y674255D01*
X1961730Y675130D01*
X1957800Y676880D01*
X1956927Y678922D01*
X1957364Y680380D01*
X1958237Y681255D01*
X1959547Y681546D01*
X1960857Y681255D01*
X1962167Y680380D01*
G01X1973772Y677755D02*
X1980759D01*
X1980104Y679797D01*
X1979012Y680963D01*
X1977484Y681546D01*
X1975955Y681255D01*
X1974645Y680380D01*
X1973772Y678338D01*
X1973335Y676588D01*
Y674838D01*
X1973772Y673088D01*
X1974864Y671338D01*
X1976174Y670172D01*
X1977702Y669880D01*
X1979230Y670463D01*
X1980759Y672213D01*
G01X1998477Y687380D02*
Y669880D01*
G01Y672504D02*
X1997604Y671046D01*
X1996293Y670172D01*
X1994765Y669880D01*
X1993019Y670463D01*
X1991709Y671921D01*
X1990835Y673671D01*
X1990617Y675713D01*
X1990835Y677755D01*
X1991709Y679505D01*
X1993019Y680963D01*
X1994765Y681546D01*
X1996293Y681255D01*
X1997385Y680671D01*
X1998477Y679505D01*
G01X3937Y0D02*
X116260D01*
G01X0Y3937D02*
G03X3937Y0I3937J0D01*
G01X0Y723480D02*
Y3937D01*
G01X416Y725241D02*
G03X0Y723480I3521J-1761D01*
G01X18597Y761603D02*
X416Y725241D01*
G01X77756Y98425D02*
G03X63976I-6890J0D01*
G01D02*
G03X77756I6890J0D01*
G01X83071Y245079D02*
G03Y231693I0J-6693D01*
G01X77756Y472441D02*
G03X63976I-6890J0D01*
G01D02*
G03X77756I6890J0D01*
G01X57087Y740157D02*
G03X41339I-7874J0D01*
G01D02*
G03X57087I7874J0D01*
G01X22118Y763780D02*
G03X18597Y761603I1J-3937D01*
G01X386149Y763780D02*
X22118D01*
G01X128071Y3937D02*
G03X132008Y0I3937J0D01*
G01X116260D02*
G03X120197Y3937I0J3937D01*
G01X132008Y0D02*
X275709D01*
G01X120197Y3937D02*
Y429331D01*
G01X128071Y59055D02*
Y3937D01*
G01Y59055D02*
G03X120197I-3937J0D01*
G01X128071D02*
G03X120197I-3937J0D01*
G01X128071Y98425D02*
Y421457D01*
G01X120197Y98425D02*
G03X128071I3937J0D01*
G01X120197D02*
G03X128071I3937J0D01*
G01X96457Y231693D02*
G03Y245079I0J6693D01*
G01X83071D02*
X96457D01*
G01Y231693D02*
X83071D01*
G01X96654Y413583D02*
G03X83661I-6496J0D01*
G01D02*
G03X96654I6496J0D01*
G01X132008Y425394D02*
G03X128071Y421457I0J-3937D01*
G01X124134Y433268D02*
X283583D01*
G01X124134D02*
G03X120197Y429331I0J-3937D01*
G01X184173Y425394D02*
X132008D01*
G01X213480Y37075D02*
G03I-4291J0D01*
G01Y383483D02*
G03I-4291J0D01*
G01X184173Y425394D02*
G03Y433268I0J3937D01*
G01Y425394D02*
G03Y433268I0J3937D01*
G01X171457Y669291D02*
G03X154921I-8268J0D01*
G01D02*
G03X171457I8268J0D01*
G01X223543Y425394D02*
X275709D01*
G01X223543Y433268D02*
G03Y425394I0J-3937D01*
G01Y433268D02*
G03Y425394I0J-3937D01*
G01X275709Y0D02*
G03X279646Y3937I0J3937D01*
G01X291457Y0D02*
X921260D01*
G01X287520Y3937D02*
G03X291457Y0I3937J0D01*
G01X287520Y429331D02*
Y3937D01*
G01X279646Y59055D02*
Y3937D01*
G01X287520Y59055D02*
G03X279646I-3937J0D01*
G01X287520D02*
G03X279646I-3937J0D01*
G01Y98425D02*
Y421457D01*
G01Y98425D02*
G03X287520I3937J0D01*
G01X279646D02*
G03X287520I3937J0D01*
G01X315551Y157677D02*
G03X302559I-6496J0D01*
G01D02*
G03X315551I6496J0D01*
G01X315945Y406890D02*
G03Y420276I0J6693D01*
G01X302559D02*
X315945D01*
G01X302559D02*
G03Y406890I0J-6693D01*
G01X315945D02*
X302559D01*
G01X279646Y421457D02*
G03X275709Y425394I-3937J0D01*
G01X287520Y429331D02*
G03X283583Y433268I-3937J0D01*
G01X321850Y472441D02*
G03X308071I-6889J0D01*
G01D02*
G03X321850I6889J0D01*
G01X412402Y39370D02*
G03X398622I-6890J0D01*
G01D02*
G03X412402I6890J0D01*
G01X371063Y740157D02*
G03X357283I-6890J0D01*
G01D02*
G03X371063I6890J0D01*
G01X403756Y763780D02*
G03X400235Y758082I0J-3937D01*
G01X389671Y761603D02*
G03X386149Y763780I-3522J-1760D01*
G01X414895Y728762D02*
X400235Y758082D01*
G01X407852Y725241D02*
X389671Y761603D01*
G01X403756Y763780D02*
X428096D01*
G01X416142Y200787D02*
G03X420079Y196850I3937J0D01*
G01X408268Y188976D02*
Y723480D01*
G01Y188976D02*
G03X412205I1968J0D01*
G01X556299Y196850D02*
X420079D01*
G01X564173Y188976D02*
X412205D01*
G01X416142Y316929D02*
Y200787D01*
G01Y316929D02*
G03X408268I-3937J0D01*
G01X416142D02*
G03X408268I-3937J0D01*
G01X416142Y347638D02*
Y690803D01*
G01X408268Y347638D02*
G03X416142I3937J0D01*
G01X408268D02*
G03X416142I3937J0D01*
G01Y721512D02*
Y723481D01*
G01Y723482D02*
G03X414894Y728764I-11811J-2D01*
G01X408268Y723480D02*
G03X407852Y725241I-3937J0D01*
G01X408268Y721512D02*
G03X416142I3937J0D01*
G01Y690803D02*
G03X408268I-3937J0D01*
G01Y721512D02*
G03X416142I3937J0D01*
G01Y690803D02*
G03X408268I-3937J0D01*
G01X428096Y763780D02*
G03X435970I3937J0D01*
G01D02*
X572622D01*
G01X483800Y137224D02*
G03X493878I5039J0D01*
G01X493563Y164744D02*
G03X484115I-4724J0D01*
G01D02*
G03X493563I4724J0D01*
G01X493878Y137224D02*
G03X483800I-5039J0D01*
G01X493622Y245605D02*
G03I-4291J0D01*
G01Y698924D02*
G03I-4291J0D01*
G01X556299Y196850D02*
G03X560236Y200787I0J3937D01*
G01X564173Y188976D02*
G03X568110I1968J0D01*
G01Y723480D02*
Y188976D01*
G01X560236Y316929D02*
Y200787D01*
G01X568110Y316929D02*
G03X560236I-3937J0D01*
G01X568110D02*
G03X560236I-3937J0D01*
G01Y690803D02*
Y347638D01*
G01D02*
G03X568110I3937J0D01*
G01X560236D02*
G03X568110I3937J0D01*
G01X560236Y721512D02*
Y723481D01*
G01X561484Y728764D02*
G03X560236Y723482I10563J-5284D01*
G01X568526Y725241D02*
G03X568110Y723480I3521J-1761D01*
G01X560236Y721512D02*
G03X568110I3937J0D01*
G01Y690803D02*
G03X560236I-3937J0D01*
G01Y721512D02*
G03X568110I3937J0D01*
G01Y690803D02*
G03X560236I-3937J0D01*
G01X576143Y758082D02*
G03X572622Y763780I-3521J1761D01*
G01X576143Y758082D02*
X561483Y728762D01*
G01X586707Y761603D02*
X568526Y725241D01*
G01X590228Y763780D02*
G03X586707Y761603I1J-3937D01*
G01X903079Y763780D02*
X590228D01*
G01X634252Y57874D02*
G03X625591I-4331J0D01*
G01D02*
G03X634252I4331J0D01*
G01X658661Y180000D02*
G03X646850I-5905J0D01*
G01D02*
G03X658661I5906J0D01*
G01X619094Y433071D02*
G03X605315I-6889J0D01*
G01D02*
G03X619094I6890J0D01*
G01Y740157D02*
G03X605315I-6889J0D01*
G01D02*
G03X619094I6890J0D01*
G01X712992Y57874D02*
G03X704331I-4331J0D01*
G01D02*
G03X712992I4330J0D01*
G01X859449Y332598D02*
G03X871260I5905J0D01*
G01D02*
G03X859449I-5906J0D01*
G01X921260Y0D02*
G03X925197Y3937I0J3937D01*
G01X883858Y59055D02*
G03X868110I-7874J0D01*
G01D02*
G03X883858I7874J0D01*
G01X925197Y3937D02*
Y723480D01*
G01X882874Y433071D02*
G03X869094I-6890J0D01*
G01D02*
G03X882874I6890J0D01*
G01X925197Y723480D02*
G03X924781Y725241I-3937J0D01*
G01X882874Y740157D02*
G03X869094I-6890J0D01*
G01D02*
G03X882874I6890J0D01*
G01X906600Y761603D02*
G03X903079Y763780I-3522J-1760D01*
G01X924781Y725241D02*
X906600Y761603D01*
G54D12*
G01X127320Y571450D02*
G02X127490Y571041I-408J-410D01*
G01X128451Y572582D02*
G02X129090Y571042I-1539J-1541D01*
G01X126947Y573220D02*
G02X128428Y572605I0J-2091D01*
G01X126947Y571620D02*
G02X127294Y571475I-1J-490D01*
G01X128451Y572582D02*
G02X129090Y571042I-1539J-1541D01*
G01X126947Y573220D02*
G02X128428Y572605I0J-2091D01*
G01X116738Y571620D02*
X126947D01*
G01X116738Y573220D02*
X126947D01*
G01X113236Y575122D02*
G03X116738Y571620I3502J0D01*
G01X114836Y575122D02*
G03X116738Y573220I1902J0D01*
G01X116737Y577023D02*
G03X114836Y575122I0J-1901D01*
G01X116737Y578623D02*
G03X113236Y575122I0J-3501D01*
G01X114836D02*
G03X116738Y573220I1902J0D01*
G01X116737Y577023D02*
G03X114836Y575122I0J-1901D01*
G01X128623Y578623D02*
X116737D01*
G01X128623Y577023D02*
X116737D01*
G01X132158Y577159D02*
G03X128623Y578623I-3535J-3536D01*
G01X131026Y576027D02*
G03X128623Y577023I-2404J-2403D01*
G01X133040Y576277D02*
X132158Y577159D01*
G01X131908Y575145D02*
X131026Y576027D01*
G01X136575Y574813D02*
G02X133040Y576277I0J5000D01*
G01X136575Y573213D02*
G02X131908Y575145I-1J6600D01*
G01X142186Y574813D02*
X136575D01*
G01X142186Y573213D02*
X136575D01*
G01X145721Y573349D02*
G03X142186Y574813I-3535J-3536D01*
G01X144589Y572217D02*
G03X142186Y573213I-2404J-2403D01*
G01X127320Y571450D02*
G02X127490Y571041I-408J-410D01*
G01X128451Y572582D02*
G02X129090Y571042I-1539J-1541D01*
G01X126947Y573220D02*
G02X128428Y572605I0J-2091D01*
G01X126947Y571620D02*
G02X127294Y571475I-1J-490D01*
G01X128451Y572582D02*
G02X129090Y571042I-1539J-1541D01*
G01X126947Y573220D02*
G02X128428Y572605I0J-2091D01*
G01X116738Y571620D02*
X126947D01*
G01X116738Y573220D02*
X126947D01*
G01X113236Y575122D02*
G03X116738Y571620I3502J0D01*
G01X114836Y575122D02*
G03X116738Y573220I1902J0D01*
G01X116737Y577023D02*
G03X114836Y575122I0J-1901D01*
G01X116737Y578623D02*
G03X113236Y575122I0J-3501D01*
G01X114836D02*
G03X116738Y573220I1902J0D01*
G01X116737Y577023D02*
G03X114836Y575122I0J-1901D01*
G01X128623Y578623D02*
X116737D01*
G01X128623Y577023D02*
X116737D01*
G01X132158Y577159D02*
G03X128623Y578623I-3535J-3536D01*
G01X131026Y576027D02*
G03X128623Y577023I-2404J-2403D01*
G01X133040Y576277D02*
X132158Y577159D01*
G01X131908Y575145D02*
X131026Y576027D01*
G01X136575Y574813D02*
G02X133040Y576277I0J5000D01*
G01X136575Y573213D02*
G02X131908Y575145I-1J6600D01*
G01X142186Y574813D02*
X136575D01*
G01X142186Y573213D02*
X136575D01*
G01X145721Y573349D02*
G03X142186Y574813I-3535J-3536D01*
G01X144589Y572217D02*
G03X142186Y573213I-2404J-2403D01*
G01X128451Y572582D02*
G02X129090Y571042I-1539J-1541D01*
G01X127320Y571450D02*
G02X127490Y571041I-408J-410D01*
G01X126947Y571620D02*
G02X127294Y571475I-1J-490D01*
G01X126947Y573220D02*
G02X128428Y572605I0J-2091D01*
G01X127320Y571450D02*
G02X127490Y571041I-408J-410D01*
G01X126947Y571620D02*
G02X127294Y571475I-1J-490D01*
G01X116738Y573220D02*
X126947D01*
G01X116738Y571620D02*
X126947D01*
G01X114836Y575122D02*
G03X116738Y573220I1902J0D01*
G01X113236Y575122D02*
G03X116738Y571620I3502J0D01*
G01X116737Y578623D02*
G03X113236Y575122I0J-3501D01*
G01X116737Y577023D02*
G03X114836Y575122I0J-1901D01*
G01X113236D02*
G03X116738Y571620I3502J0D01*
G01X116737Y578623D02*
G03X113236Y575122I0J-3501D01*
G01X128623Y577023D02*
X116737D01*
G01X128623Y578623D02*
X116737D01*
G01X131026Y576027D02*
G03X128623Y577023I-2404J-2403D01*
G01X132158Y577159D02*
G03X128623Y578623I-3535J-3536D01*
G01X131908Y575145D02*
X131026Y576027D01*
G01X133040Y576277D02*
X132158Y577159D01*
G01X136575Y573213D02*
G02X131908Y575145I-1J6600D01*
G01X136575Y574813D02*
G02X133040Y576277I0J5000D01*
G01X142186Y573213D02*
X136575D01*
G01X142186Y574813D02*
X136575D01*
G01X144589Y572217D02*
G03X142186Y573213I-2404J-2403D01*
G01X145721Y573349D02*
G03X142186Y574813I-3535J-3536D01*
G01X128451Y572582D02*
G02X129090Y571042I-1539J-1541D01*
G01X127320Y571450D02*
G02X127490Y571041I-408J-410D01*
G01X126947Y571620D02*
G02X127294Y571475I-1J-490D01*
G01X126947Y573220D02*
G02X128428Y572605I0J-2091D01*
G01X127320Y571450D02*
G02X127490Y571041I-408J-410D01*
G01X126947Y571620D02*
G02X127294Y571475I-1J-490D01*
G01X116738Y573220D02*
X126947D01*
G01X116738Y571620D02*
X126947D01*
G01X114836Y575122D02*
G03X116738Y573220I1902J0D01*
G01X113236Y575122D02*
G03X116738Y571620I3502J0D01*
G01X116737Y578623D02*
G03X113236Y575122I0J-3501D01*
G01X116737Y577023D02*
G03X114836Y575122I0J-1901D01*
G01X113236D02*
G03X116738Y571620I3502J0D01*
G01X116737Y578623D02*
G03X113236Y575122I0J-3501D01*
G01X128623Y577023D02*
X116737D01*
G01X128623Y578623D02*
X116737D01*
G01X131026Y576027D02*
G03X128623Y577023I-2404J-2403D01*
G01X132158Y577159D02*
G03X128623Y578623I-3535J-3536D01*
G01X131908Y575145D02*
X131026Y576027D01*
G01X133040Y576277D02*
X132158Y577159D01*
G01X136575Y573213D02*
G02X131908Y575145I-1J6600D01*
G01X136575Y574813D02*
G02X133040Y576277I0J5000D01*
G01X142186Y573213D02*
X136575D01*
G01X142186Y574813D02*
X136575D01*
G01X144589Y572217D02*
G03X142186Y573213I-2404J-2403D01*
G01X145721Y573349D02*
G03X142186Y574813I-3535J-3536D01*
G01X152400Y585714D02*
X153368D01*
G01X152399Y587314D02*
X153368D01*
G01X150050Y586687D02*
G03X152400Y585714I2349J2348D01*
G01X151182Y587818D02*
G03X152399Y587314I1217J1217D01*
G01X149264Y587472D02*
X150050Y586686D01*
G01X150396Y588604D02*
X151182Y587818D01*
G01X147750Y588100D02*
G02X149264Y587472I-1J-2142D01*
G01X147750Y589700D02*
G02X150396Y588604I0J-3742D01*
G01X146724Y588100D02*
X147750D01*
G01X146724Y589700D02*
X147750D01*
G01X149864Y578130D02*
X153632D01*
G01X153631Y576530D02*
X149963D01*
G01X152399Y587314D02*
X153368D01*
G01X152400Y585714D02*
X153368D01*
G01X151182Y587818D02*
G03X152399Y587314I1217J1217D01*
G01X150050Y586687D02*
G03X152400Y585714I2349J2348D01*
G01X150396Y588604D02*
X151182Y587818D01*
G01X149264Y587472D02*
X150050Y586686D01*
G01X147750Y589700D02*
G02X150396Y588604I0J-3742D01*
G01X147750Y588100D02*
G02X149264Y587472I-1J-2142D01*
G01X146724Y589700D02*
X147750D01*
G01X146724Y588100D02*
X147750D01*
G01X153631Y576530D02*
X149963D01*
G01X149864Y578130D02*
X153632D01*
G01X152400Y585714D02*
X153368D01*
G01X152399Y587314D02*
X153368D01*
G01X150050Y586687D02*
G03X152400Y585714I2349J2348D01*
G01X151182Y587818D02*
G03X152399Y587314I1217J1217D01*
G01X149264Y587472D02*
X150050Y586686D01*
G01X150396Y588604D02*
X151182Y587818D01*
G01X147750Y588100D02*
G02X149264Y587472I-1J-2142D01*
G01X147750Y589700D02*
G02X150396Y588604I0J-3742D01*
G01X146724Y588100D02*
X147750D01*
G01X146724Y589700D02*
X147750D01*
G01X152399Y587314D02*
X153368D01*
G01X152400Y585714D02*
X153368D01*
G01X151182Y587818D02*
G03X152399Y587314I1217J1217D01*
G01X150050Y586687D02*
G03X152400Y585714I2349J2348D01*
G01X150396Y588604D02*
X151182Y587818D01*
G01X149264Y587472D02*
X150050Y586686D01*
G01X147750Y589700D02*
G02X150396Y588604I0J-3742D01*
G01X147750Y588100D02*
G02X149264Y587472I-1J-2142D01*
G01X146724Y589700D02*
X147750D01*
G01X146724Y588100D02*
X147750D01*
G01X149416Y571725D02*
G02X145881Y573189I0J5000D01*
G01X149416Y570125D02*
G02X144749Y572057I-1J6600D01*
G01X153400Y571725D02*
X149416D01*
G01X153400Y570125D02*
X149416D01*
G01Y571725D02*
G02X145881Y573189I0J5000D01*
G01X149416Y570125D02*
G02X144749Y572057I-1J6600D01*
G01X153400Y571725D02*
X149416D01*
G01X153400Y570125D02*
X149416D01*
G01D02*
G02X144749Y572057I-1J6600D01*
G01X149416Y571725D02*
G02X145881Y573189I0J5000D01*
G01X153400Y570125D02*
X149416D01*
G01X153400Y571725D02*
X149416D01*
G01Y570125D02*
G02X144749Y572057I-1J6600D01*
G01X149416Y571725D02*
G02X145881Y573189I0J5000D01*
G01X153400Y570125D02*
X149416D01*
G01X153400Y571725D02*
X149416D01*
G01X149864Y578130D02*
X153632D01*
G01X153631Y576530D02*
X149963D01*
G01X153631D02*
X149963D01*
G01X149864Y578130D02*
X153632D01*
G01X808522Y264268D02*
X804819D01*
G01X805582Y262668D02*
X807859D01*
G01X811368Y261422D02*
X808522Y264268D01*
G01X807859Y262668D02*
X809768Y260759D01*
G01X811368Y258077D02*
Y261422D01*
G01X809768Y260759D02*
Y257414D01*
G01X813938Y255507D02*
X811368Y258077D01*
G01X809768Y257414D02*
X813275Y253907D01*
G01X817725Y255507D02*
X813938D01*
G01X813275Y253907D02*
X817711D01*
G01X830268Y248946D02*
X831619Y250297D01*
G01X832751Y249166D02*
X830931Y247346D01*
G01X828717Y248946D02*
X830268D01*
G01X830931Y247346D02*
X828054D01*
G01X826604Y251059D02*
X828717Y248946D01*
G01X828054Y247346D02*
X825004Y250396D01*
G01X826604Y252368D02*
Y251059D01*
G01X825004Y250396D02*
Y251704D01*
G01X823486Y255485D02*
X826604Y252368D01*
G01X825004Y251704D02*
X822823Y253885D01*
G01X820533Y255485D02*
X823486D01*
G01X822823Y253885D02*
X820503D01*
G01X813275Y253907D02*
X817711D01*
G01X817725Y255507D02*
X813938D01*
G01X809768Y257414D02*
X813275Y253907D01*
G01X813938Y255507D02*
X811368Y258077D01*
G01X809768Y260759D02*
Y257414D01*
G01X811368Y258077D02*
Y261422D01*
G01X807859Y262668D02*
X809768Y260759D01*
G01X811368Y261422D02*
X808522Y264268D01*
G01X805582Y262668D02*
X807859D01*
G01X808522Y264268D02*
X804819D01*
G01X822823Y253885D02*
X820503D01*
G01X820533Y255485D02*
X823486D01*
G01X825004Y251704D02*
X822823Y253885D01*
G01X823486Y255485D02*
X826604Y252368D01*
G01X825004Y250396D02*
Y251704D01*
G01X826604Y252368D02*
Y251059D01*
G01X828054Y247346D02*
X825004Y250396D01*
G01X826604Y251059D02*
X828717Y248946D01*
G01X830931Y247346D02*
X828054D01*
G01X828717Y248946D02*
X830268D01*
G01X832751Y249166D02*
X830931Y247346D01*
G01X830268Y248946D02*
X831619Y250297D01*
G01X814865Y262106D02*
X809649Y267322D01*
G01X808986Y265722D02*
X814202Y260506D01*
G01X817724Y262106D02*
X814865D01*
G01X814202Y260506D02*
X817712D01*
G01X824957Y262043D02*
X820575D01*
G01X824294Y260443D02*
X820461D01*
G01X828435Y258565D02*
X824957Y262043D01*
G01X827772Y256965D02*
X824294Y260443D01*
G01X830932Y258565D02*
X828435D01*
G01X831595Y256965D02*
X827772D01*
G01X832283Y259916D02*
X830932Y258565D01*
G01X833415Y258785D02*
X831595Y256965D01*
G01X814202Y260506D02*
X817712D01*
G01X817724Y262106D02*
X814865D01*
G01X808986Y265722D02*
X814202Y260506D01*
G01X814865Y262106D02*
X809649Y267322D01*
G01X824294Y260443D02*
X820461D01*
G01X824957Y262043D02*
X820575D01*
G01X827772Y256965D02*
X824294Y260443D01*
G01X828435Y258565D02*
X824957Y262043D01*
G01X831595Y256965D02*
X827772D01*
G01X830932Y258565D02*
X828435D01*
G01X833415Y258785D02*
X831595Y256965D01*
G01X832283Y259916D02*
X830932Y258565D01*
G01X836671Y265000D02*
X837936Y266265D01*
G01X837334Y263400D02*
X839067Y265133D01*
G01X834337Y263400D02*
X837334D01*
G01X831450Y268550D02*
X835000Y265000D01*
G01X830787Y266950D02*
X834337Y263400D01*
G01X837334D02*
X839067Y265133D01*
G01X836671Y265000D02*
X837936Y266265D01*
G01X834337Y263400D02*
X837334D01*
G01X830787Y266950D02*
X834337Y263400D01*
G01X831450Y268550D02*
X835000Y265000D01*
G01X807846Y273621D02*
X804725D01*
G01X804500Y272021D02*
X808509D01*
G01X808882Y274657D02*
X807846Y273621D01*
G01X808509Y272021D02*
X809545Y273057D01*
G01X811514Y274657D02*
X808882D01*
G01X809545Y273057D02*
X810851D01*
G01X815124Y271047D02*
X811514Y274657D01*
G01X810851Y273057D02*
X813524Y270384D01*
G01X815124Y269312D02*
Y271047D01*
G01X813524Y270384D02*
Y268649D01*
G01X815736Y268700D02*
X815124Y269312D01*
G01X813524Y268649D02*
X815073Y267100D01*
G01X817718Y268700D02*
X815736D01*
G01X815073Y267100D02*
X817718D01*
G01X815073D02*
X817718D01*
G01Y268700D02*
X815736D01*
G01X813524Y268649D02*
X815073Y267100D01*
G01X815736Y268700D02*
X815124Y269312D01*
G01X813524Y270384D02*
Y268649D01*
G01X815124Y269312D02*
Y271047D01*
G01X810851Y273057D02*
X813524Y270384D01*
G01X815124Y271047D02*
X811514Y274657D01*
G01X809545Y273057D02*
X810851D01*
G01X811514Y274657D02*
X808882D01*
G01X808509Y272021D02*
X809545Y273057D01*
G01X808882Y274657D02*
X807846Y273621D01*
G01X804500Y272021D02*
X808509D01*
G01X807846Y273621D02*
X804725D01*
G01X813825Y277147D02*
X805100D01*
G01X805763Y275547D02*
X813161D01*
G01X815610Y275361D02*
X813825Y277147D01*
G01X813161Y275547D02*
X814946Y273761D01*
G01X817779Y275361D02*
X815610D01*
G01X814946Y273761D02*
X817657D01*
G01X843063Y271192D02*
X843936Y272065D01*
G01X843726Y269592D02*
X845067Y270933D01*
G01X840907Y271192D02*
X843063D01*
G01X840244Y269592D02*
X843726D01*
G01X836899Y275200D02*
X840907Y271192D01*
G01X836236Y273600D02*
X840244Y269592D01*
G01X820618Y275200D02*
X836899D01*
G01X820418Y273600D02*
X836236D01*
G01X814946Y273761D02*
X817657D01*
G01X817779Y275361D02*
X815610D01*
G01X813161Y275547D02*
X814946Y273761D01*
G01X815610Y275361D02*
X813825Y277147D01*
G01X805763Y275547D02*
X813161D01*
G01X813825Y277147D02*
X805100D01*
G01X843726Y269592D02*
X845067Y270933D01*
G01X843063Y271192D02*
X843936Y272065D01*
G01X840244Y269592D02*
X843726D01*
G01X840907Y271192D02*
X843063D01*
G01X836236Y273600D02*
X840244Y269592D01*
G01X836899Y275200D02*
X840907Y271192D01*
G01X820418Y273600D02*
X836236D01*
G01X820618Y275200D02*
X836899D01*
G01X805690Y283071D02*
X804724D01*
G01X802830Y281470D02*
X806352D01*
G01X814577Y283394D02*
X806013D01*
G01X806676Y281794D02*
X813914D01*
G01X816196Y281775D02*
X814577Y283394D01*
G01X813914Y281794D02*
X815534Y280174D01*
G01X817593Y281775D02*
X816196D01*
G01X815534Y280174D02*
X817844D01*
G01X838778Y281907D02*
X820511D01*
G01X839441Y280307D02*
X820525D01*
G01X841935Y285064D02*
X838778Y281907D01*
G01X843067Y283933D02*
X839441Y280307D01*
G01X815534Y280174D02*
X817844D01*
G01X817593Y281775D02*
X816196D01*
G01X813914Y281794D02*
X815534Y280174D01*
G01X816196Y281775D02*
X814577Y283394D01*
G01X806676Y281794D02*
X813914D01*
G01X814577Y283394D02*
X806013D01*
G01X802830Y281470D02*
X806352D01*
G01X805690Y283071D02*
X804724D01*
G01X839441Y280307D02*
X820525D01*
G01X838778Y281907D02*
X820511D01*
G01X843067Y283933D02*
X839441Y280307D01*
G01X841935Y285064D02*
X838778Y281907D01*
G01X809029Y286220D02*
X804724D01*
G01X802779Y284620D02*
X809692D01*
G01X811331Y288522D02*
X809029Y286220D01*
G01X809692Y284620D02*
X811994Y286922D01*
G01X817740Y288522D02*
X811331D01*
G01X811994Y286922D02*
X817696D01*
G01X829304Y288504D02*
X820514D01*
G01X829967Y286904D02*
X820522D01*
G01X835000Y294200D02*
X829304Y288504D01*
G01X835663Y292600D02*
X829967Y286904D01*
G01X840700Y294200D02*
X835000D01*
G01X840037Y292600D02*
X835663D01*
G01X845208Y289692D02*
X840700Y294200D01*
G01X844545Y288092D02*
X840037Y292600D01*
G01X846563Y289692D02*
X845208D01*
G01X847226Y288092D02*
X844545D01*
G01X847436Y290565D02*
X846563Y289692D01*
G01X848567Y289433D02*
X847226Y288092D01*
G01X811994Y286922D02*
X817696D01*
G01X817740Y288522D02*
X811331D01*
G01X809692Y284620D02*
X811994Y286922D01*
G01X811331Y288522D02*
X809029Y286220D01*
G01X802779Y284620D02*
X809692D01*
G01X809029Y286220D02*
X804724D01*
G01X829967Y286904D02*
X820522D01*
G01X829304Y288504D02*
X820514D01*
G01X835663Y292600D02*
X829967Y286904D01*
G01X835000Y294200D02*
X829304Y288504D01*
G01X840037Y292600D02*
X835663D01*
G01X840700Y294200D02*
X835000D01*
G01X844545Y288092D02*
X840037Y292600D01*
G01X845208Y289692D02*
X840700Y294200D01*
G01X847226Y288092D02*
X844545D01*
G01X846563Y289692D02*
X845208D01*
G01X848567Y289433D02*
X847226Y288092D01*
G01X847436Y290565D02*
X846563Y289692D01*
G01X806839Y292412D02*
X804831D01*
G01X804300Y290812D02*
X807502D01*
G01X809402Y294975D02*
X806839Y292412D01*
G01X807502Y290812D02*
X810065Y293375D01*
G01X817593Y294975D02*
X809402D01*
G01X810065Y293375D02*
X817843D01*
G01X852271Y295400D02*
X853435Y296564D01*
G01X854567Y295433D02*
X852934Y293800D01*
G01X850600Y295400D02*
X852271D01*
G01X852934Y293800D02*
X849937D01*
G01X845100Y300900D02*
X850600Y295400D01*
G01X849937Y293800D02*
X844437Y299300D01*
G01X833900Y300900D02*
X845100D01*
G01X844437Y299300D02*
X834563D01*
G01X828000Y295000D02*
X833900Y300900D01*
G01X834563Y299300D02*
X828663Y293400D01*
G01X820618Y295000D02*
X828000D01*
G01X828663Y293400D02*
X820418D01*
G01X810065Y293375D02*
X817843D01*
G01X817593Y294975D02*
X809402D01*
G01X807502Y290812D02*
X810065Y293375D01*
G01X809402Y294975D02*
X806839Y292412D01*
G01X804300Y290812D02*
X807502D01*
G01X806839Y292412D02*
X804831D01*
G01X828663Y293400D02*
X820418D01*
G01X820618Y295000D02*
X828000D01*
G01X834563Y299300D02*
X828663Y293400D01*
G01X828000Y295000D02*
X833900Y300900D01*
G01X844437Y299300D02*
X834563D01*
G01X833900Y300900D02*
X845100D01*
G01X849937Y293800D02*
X844437Y299300D01*
G01X845100Y300900D02*
X850600Y295400D01*
G01X852934Y293800D02*
X849937D01*
G01X850600Y295400D02*
X852271D01*
G01X854567Y295433D02*
X852934Y293800D01*
G01X852271Y295400D02*
X853435Y296564D01*
G01X812058Y301675D02*
X817693D01*
G01X812721Y300075D02*
X817743D01*
G01X806052Y295669D02*
X812058Y301675D01*
G01X806715Y294069D02*
X812721Y300075D01*
G01X804724Y295669D02*
X806052D01*
G01X806715Y294069D02*
X812721Y300075D01*
G01X804200Y294069D02*
X806715D01*
G01X826055Y301555D02*
X820663D01*
G01X826718Y299955D02*
X820373D01*
G01X831500Y307000D02*
X826055Y301555D01*
G01X832163Y305400D02*
X826718Y299955D01*
G01X843866Y307000D02*
X831500D01*
G01X844529Y305400D02*
X832163D01*
G01X848883Y312017D02*
X843866Y307000D01*
G01X846664Y307535D02*
X844529Y305400D01*
G01X850015Y310885D02*
X846665Y307535D01*
G01X812721Y300075D02*
X817743D01*
G01X812058Y301675D02*
X817693D01*
G01X806715Y294069D02*
X812721Y300075D01*
G01X806052Y295669D02*
X812058Y301675D01*
G01X804724Y295669D02*
X806052D01*
G01X804200Y294069D02*
X806715D01*
G01X804724Y295669D02*
X806052D01*
G01X826718Y299955D02*
X820373D01*
G01X826055Y301555D02*
X820663D01*
G01X832163Y305400D02*
X826718Y299955D01*
G01X831500Y307000D02*
X826055Y301555D01*
G01X844529Y305400D02*
X832163D01*
G01X843866Y307000D02*
X831500D01*
G01X846664Y307535D02*
X844529Y305400D01*
G01X848883Y312017D02*
X843866Y307000D01*
G01X850015Y310885D02*
X846665Y307535D01*
G01X848883Y312017D02*
X843866Y307000D01*
G01X809649Y267322D02*
X804725D01*
G01X804062Y265722D02*
X808986D01*
G01X804062D02*
X808986D01*
G01X809649Y267322D02*
X804725D01*
G01X835000Y265000D02*
X836671D01*
G01X820668Y268550D02*
X831450D01*
G01X820368Y266950D02*
X830787D01*
G01X835000Y265000D02*
X836671D01*
G01X820368Y266950D02*
X830787D01*
G01X820668Y268550D02*
X831450D01*
G54D13*
G01X221767Y589900D02*
X229775Y597908D01*
G01X222275Y588675D02*
X231000Y597400D01*
G01X219427Y589900D02*
X221767D01*
G01X221352Y588675D02*
X222275D01*
G01D02*
X231000Y597400D01*
G01X221767Y589900D02*
X229775Y597908D01*
G01X221352Y588675D02*
X222275D01*
G01X219427Y589900D02*
X221767D01*
G01X222963Y584102D02*
X221803D01*
G01X223471Y582877D02*
X221853D01*
G01X227769Y587175D02*
X223471Y582877D01*
G01X227261Y588400D02*
X222963Y584102D01*
G01X227769Y587175D02*
X223471Y582877D01*
G01X230652Y588400D02*
X227261D01*
G01X231160Y587175D02*
X227769D01*
G01X237377Y595125D02*
X230652Y588400D01*
G01X237885Y593900D02*
X231160Y587175D01*
G01X223471Y582877D02*
X221853D01*
G01X222963Y584102D02*
X221803D01*
G01X227769Y587175D02*
X223471Y582877D01*
G01X222963Y584102D02*
X221803D01*
G01X227261Y588400D02*
X222963Y584102D01*
G01X231160Y587175D02*
X227769D01*
G01X230652Y588400D02*
X227261D01*
G01X237885Y593900D02*
X231160Y587175D01*
G01X237377Y595125D02*
X230652Y588400D01*
G01X221767Y589900D02*
X229775Y597908D01*
G01X222275Y588675D02*
X231000Y597400D01*
G01X219427Y589900D02*
X221767D01*
G01X221352Y588675D02*
X222275D01*
G01D02*
X231000Y597400D01*
G01X221767Y589900D02*
X229775Y597908D01*
G01X221352Y588675D02*
X222275D01*
G01X219427Y589900D02*
X221767D01*
G01X222963Y584102D02*
X221803D01*
G01X223471Y582877D02*
X221853D01*
G01X227769Y587175D02*
X223471Y582877D01*
G01X227261Y588400D02*
X222963Y584102D01*
G01X227769Y587175D02*
X223471Y582877D01*
G01X230652Y588400D02*
X227261D01*
G01X231160Y587175D02*
X227769D01*
G01X237377Y595125D02*
X230652Y588400D01*
G01X237885Y593900D02*
X231160Y587175D01*
G01X223471Y582877D02*
X221853D01*
G01X222963Y584102D02*
X221803D01*
G01X227769Y587175D02*
X223471Y582877D01*
G01X222963Y584102D02*
X221803D01*
G01X227261Y588400D02*
X222963Y584102D01*
G01X231160Y587175D02*
X227769D01*
G01X230652Y588400D02*
X227261D01*
G01X237885Y593900D02*
X231160Y587175D01*
G01X237377Y595125D02*
X230652Y588400D01*
G01X256025Y608925D02*
X257379D01*
G01X256533Y607700D02*
X257377D01*
G01X253725Y606625D02*
X256025Y608925D01*
G01X254233Y605400D02*
X256533Y607700D01*
G01X247835Y606625D02*
X253725D01*
G01X247327Y605400D02*
X254233D01*
G01X246180Y608280D02*
X247835Y606625D01*
G01X245672Y607055D02*
X247327Y605400D01*
G01X238460Y608280D02*
X246180D01*
G01X238968Y607055D02*
X245672D01*
G01X229775Y599595D02*
X238460Y608280D01*
G01X231000Y599087D02*
X238968Y607055D01*
G01X229775Y597908D02*
Y599595D01*
G01X231000Y597400D02*
Y599087D01*
G01X256533Y607700D02*
X257377D01*
G01X256025Y608925D02*
X257379D01*
G01X254233Y605400D02*
X256533Y607700D01*
G01X253725Y606625D02*
X256025Y608925D01*
G01X247327Y605400D02*
X254233D01*
G01X247835Y606625D02*
X253725D01*
G01X245672Y607055D02*
X247327Y605400D01*
G01X246180Y608280D02*
X247835Y606625D01*
G01X238968Y607055D02*
X245672D01*
G01X238460Y608280D02*
X246180D01*
G01X231000Y599087D02*
X238968Y607055D01*
G01X229775Y599595D02*
X238460Y608280D01*
G01X231000Y597400D02*
Y599087D01*
G01X229775Y597908D02*
Y599595D01*
G01X243925Y595125D02*
X237377D01*
G01X244433Y593900D02*
X237885D01*
G01X249225Y600425D02*
X243925Y595125D01*
G01X249733Y599200D02*
X244433Y593900D01*
G01X250257Y600425D02*
X249225D01*
G01X250220Y599200D02*
X249733D01*
G01X244433Y593900D02*
X237885D01*
G01X243925Y595125D02*
X237377D01*
G01X249733Y599200D02*
X244433Y593900D01*
G01X249225Y600425D02*
X243925Y595125D01*
G01X250220Y599200D02*
X249733D01*
G01X250257Y600425D02*
X249225D01*
G01X256025Y608925D02*
X257379D01*
G01X256533Y607700D02*
X257377D01*
G01X253725Y606625D02*
X256025Y608925D01*
G01X254233Y605400D02*
X256533Y607700D01*
G01X247835Y606625D02*
X253725D01*
G01X247327Y605400D02*
X254233D01*
G01X246180Y608280D02*
X247835Y606625D01*
G01X245672Y607055D02*
X247327Y605400D01*
G01X238460Y608280D02*
X246180D01*
G01X238968Y607055D02*
X245672D01*
G01X229775Y599595D02*
X238460Y608280D01*
G01X231000Y599087D02*
X238968Y607055D01*
G01X229775Y597908D02*
Y599595D01*
G01X231000Y597400D02*
Y599087D01*
G01X256533Y607700D02*
X257377D01*
G01X256025Y608925D02*
X257379D01*
G01X254233Y605400D02*
X256533Y607700D01*
G01X253725Y606625D02*
X256025Y608925D01*
G01X247327Y605400D02*
X254233D01*
G01X247835Y606625D02*
X253725D01*
G01X245672Y607055D02*
X247327Y605400D01*
G01X246180Y608280D02*
X247835Y606625D01*
G01X238968Y607055D02*
X245672D01*
G01X238460Y608280D02*
X246180D01*
G01X231000Y599087D02*
X238968Y607055D01*
G01X229775Y599595D02*
X238460Y608280D01*
G01X231000Y597400D02*
Y599087D01*
G01X229775Y597908D02*
Y599595D01*
G01X243925Y595125D02*
X237377D01*
G01X244433Y593900D02*
X237885D01*
G01X249225Y600425D02*
X243925Y595125D01*
G01X249733Y599200D02*
X244433Y593900D01*
G01X250257Y600425D02*
X249225D01*
G01X250220Y599200D02*
X249733D01*
G01X244433Y593900D02*
X237885D01*
G01X243925Y595125D02*
X237377D01*
G01X249733Y599200D02*
X244433Y593900D01*
G01X249225Y600425D02*
X243925Y595125D01*
G01X250220Y599200D02*
X249733D01*
G01X250257Y600425D02*
X249225D01*
G01X320299Y322812D02*
X327182D01*
G01X320299Y324037D02*
X327182D01*
G01X320299D02*
X327182D01*
G01X320299Y322812D02*
X327182D01*
G01X320299Y310214D02*
X333632D01*
G01X320299Y311439D02*
X333632D01*
G01X320299D02*
X333632D01*
G01X320299Y310214D02*
X333632D01*
G01X320299Y297615D02*
X327132D01*
G01X320299Y298840D02*
X327132D01*
G01X320299D02*
X327132D01*
G01X320299Y297615D02*
X327132D01*
G01X320298Y285018D02*
X333482D01*
G01X320298Y286243D02*
X333541D01*
G01X320298D02*
X333541D01*
G01X320298Y285018D02*
X333482D01*
G01X302368Y266160D02*
X303382D01*
G01X302310Y267385D02*
X303382D01*
G01X302310D02*
X303382D01*
G01X302368Y266160D02*
X303382D01*
G01X301632Y329224D02*
X306482D01*
G01X301931Y330449D02*
X306482D01*
G01X301931D02*
X306482D01*
G01X301632Y329224D02*
X306482D01*
G01X301532Y316526D02*
X303133D01*
G01X301682Y317751D02*
X303126D01*
G01X301682D02*
X303126D01*
G01X301532Y316526D02*
X303133D01*
G01X302805Y303949D02*
X306449D01*
G01X302736Y305174D02*
X306449D01*
G01X302736D02*
X306449D01*
G01X302805Y303949D02*
X306449D01*
G01X301317Y291304D02*
X303155D01*
G01X301454Y292529D02*
X303104D01*
G01X301454D02*
X303104D01*
G01X301317Y291304D02*
X303155D01*
G01X302785Y278733D02*
X306426D01*
G01X302756Y279958D02*
X306433D01*
G01X302756D02*
X306433D01*
G01X302785Y278733D02*
X306426D01*
G01X320299Y373206D02*
X326994D01*
G01X320299Y374431D02*
X327095D01*
G01X320299D02*
X327095D01*
G01X320299Y373206D02*
X326994D01*
G01X320298Y360608D02*
X333482D01*
G01X320298Y361833D02*
X333482D01*
G01X320298D02*
X333482D01*
G01X320298Y360608D02*
X333482D01*
G01X320299Y348009D02*
X327232D01*
G01X320299Y349234D02*
X327232D01*
G01X320299D02*
X327232D01*
G01X320299Y348009D02*
X327232D01*
G01X320299Y335411D02*
X333782D01*
G01X320299Y336636D02*
X333782D01*
G01X320299D02*
X333782D01*
G01X320299Y335411D02*
X333782D01*
G01X301485Y366920D02*
X303282D01*
G01X301418Y368145D02*
X303282D01*
G01X301418D02*
X303282D01*
G01X301485Y366920D02*
X303282D01*
G01X301420Y354321D02*
X306438D01*
G01X301800Y355546D02*
X306421D01*
G01X301800D02*
X306421D01*
G01X301420Y354321D02*
X306438D01*
G01X301297Y341723D02*
X303136D01*
G01X301606Y342948D02*
X303123D01*
G01X301606D02*
X303123D01*
G01X301297Y341723D02*
X303136D01*
G01X339134Y605887D02*
X338115Y604868D01*
G01X338626Y607112D02*
X336272Y604758D01*
G01X343588Y605887D02*
X339134D01*
G01X343080Y607112D02*
X338626D01*
G01D02*
X336272Y604758D01*
G01X339134Y605887D02*
X338115Y604868D01*
G01X343080Y607112D02*
X338626D01*
G01X343588Y605887D02*
X339134D01*
G01D02*
X338115Y604868D01*
G01X338626Y607112D02*
X336272Y604758D01*
G01X343588Y605887D02*
X339134D01*
G01X343080Y607112D02*
X338626D01*
G01D02*
X336272Y604758D01*
G01X339134Y605887D02*
X338115Y604868D01*
G01X343080Y607112D02*
X338626D01*
G01X343588Y605887D02*
X339134D01*
G01X389239Y62399D02*
Y64391D01*
G01X388014Y62907D02*
Y64437D01*
G01X387947Y61107D02*
X389239Y62399D01*
G01X387439Y62332D02*
X388014Y62907D01*
G01X383960Y61107D02*
X387947D01*
G01X384468Y62332D02*
X387439D01*
G01X378452Y66615D02*
X383960Y61107D01*
G01X381622Y65178D02*
X384468Y62332D01*
G01X378960Y67840D02*
X379497Y67303D01*
G01X372865Y66615D02*
X378452D01*
G01X372810Y67840D02*
X378960D01*
G01X351711Y66617D02*
X348594Y69734D01*
G01X352218Y67843D02*
X349102Y70959D01*
G01X352725Y66617D02*
X351711D01*
G01X359537Y67843D02*
X352218D01*
G01X371132Y66618D02*
X352726D01*
G01X359537Y67843D02*
X352218D01*
G01X371193D02*
X362542D01*
G01X389239Y62399D02*
Y64391D01*
G01X388014Y62907D02*
Y64437D01*
G01X387947Y61107D02*
X389239Y62399D01*
G01X387439Y62332D02*
X388014Y62907D01*
G01X383960Y61107D02*
X387947D01*
G01X384468Y62332D02*
X387439D01*
G01X378452Y66615D02*
X383960Y61107D01*
G01X381622Y65178D02*
X384468Y62332D01*
G01X378960Y67840D02*
X379497Y67303D01*
G01X372865Y66615D02*
X378452D01*
G01X372810Y67840D02*
X378960D01*
G01X351711Y66617D02*
X348594Y69734D01*
G01X352218Y67843D02*
X349102Y70959D01*
G01X352725Y66617D02*
X351711D01*
G01X359537Y67843D02*
X352218D01*
G01X371132Y66618D02*
X352726D01*
G01X359537Y67843D02*
X352218D01*
G01X371193D02*
X362542D01*
G01X388014Y62907D02*
Y64437D01*
G01X389239Y62399D02*
Y64391D01*
G01X387439Y62332D02*
X388014Y62907D01*
G01X387947Y61107D02*
X389239Y62399D01*
G01X384468Y62332D02*
X387439D01*
G01X383960Y61107D02*
X387947D01*
G01X381622Y65178D02*
X384468Y62332D01*
G01X378452Y66615D02*
X383960Y61107D01*
G01X378960Y67840D02*
X379497Y67303D01*
G01X378452Y66615D02*
X383960Y61107D01*
G01X372810Y67840D02*
X378960D01*
G01X372865Y66615D02*
X378452D01*
G01X352218Y67843D02*
X349102Y70959D01*
G01X351711Y66617D02*
X348594Y69734D01*
G01X359537Y67843D02*
X352218D01*
G01X352725Y66617D02*
X351711D01*
G01X371132Y66618D02*
X352726D01*
G01X371193Y67843D02*
X362542D01*
G01X371132Y66618D02*
X352726D01*
G01X388014Y62907D02*
Y64437D01*
G01X389239Y62399D02*
Y64391D01*
G01X387439Y62332D02*
X388014Y62907D01*
G01X387947Y61107D02*
X389239Y62399D01*
G01X384468Y62332D02*
X387439D01*
G01X383960Y61107D02*
X387947D01*
G01X381622Y65178D02*
X384468Y62332D01*
G01X378452Y66615D02*
X383960Y61107D01*
G01X378960Y67840D02*
X379497Y67303D01*
G01X378452Y66615D02*
X383960Y61107D01*
G01X372810Y67840D02*
X378960D01*
G01X372865Y66615D02*
X378452D01*
G01X352218Y67843D02*
X349102Y70959D01*
G01X351711Y66617D02*
X348594Y69734D01*
G01X359537Y67843D02*
X352218D01*
G01X352725Y66617D02*
X351711D01*
G01X371132Y66618D02*
X352726D01*
G01X371193Y67843D02*
X362542D01*
G01X371132Y66618D02*
X352726D01*
G01X403764Y107961D02*
Y159423D01*
G01X402539Y107453D02*
Y158915D01*
G01X412177Y99548D02*
X403764Y107961D01*
G01X411669Y98323D02*
X402539Y107453D01*
G01D02*
Y158915D01*
G01X403764Y107961D02*
Y159423D01*
G01X411669Y98323D02*
X402539Y107453D01*
G01X412177Y99548D02*
X403764Y107961D01*
G01X387889Y78563D02*
Y76009D01*
G01X389114Y78351D02*
Y76306D01*
G01X403764Y107961D02*
Y159423D01*
G01X402539Y107453D02*
Y158915D01*
G01X412177Y99548D02*
X403764Y107961D01*
G01X411669Y98323D02*
X402539Y107453D01*
G01D02*
Y158915D01*
G01X403764Y107961D02*
Y159423D01*
G01X411669Y98323D02*
X402539Y107453D01*
G01X412177Y99548D02*
X403764Y107961D01*
G01X389114Y78351D02*
Y76306D01*
G01X387889Y78563D02*
Y76009D01*
G01Y78563D02*
Y76009D01*
G01X389114Y78351D02*
Y76306D01*
G01X348594Y69734D02*
X347258D01*
G01X349102Y70959D02*
X347133D01*
G01X348594Y69734D02*
X347258D01*
G01X349102Y70959D02*
X347133D01*
G01X349102D02*
X347133D01*
G01X348594Y69734D02*
X347258D01*
G01X349102Y70959D02*
X347133D01*
G01X348594Y69734D02*
X347258D01*
G01X389114Y78351D02*
Y76306D01*
G01X387889Y78563D02*
Y76009D01*
G01X402617Y160570D02*
X401541D01*
G01X402109Y159345D02*
X401341D01*
G01X403764Y159423D02*
X402617Y160570D01*
G01X402539Y158915D02*
X402109Y159345D01*
G01D02*
X401341D01*
G01X402617Y160570D02*
X401541D01*
G01X402539Y158915D02*
X402109Y159345D01*
G01X403764Y159423D02*
X402617Y160570D01*
G01D02*
X401541D01*
G01X402109Y159345D02*
X401341D01*
G01X403764Y159423D02*
X402617Y160570D01*
G01X402539Y158915D02*
X402109Y159345D01*
G01D02*
X401341D01*
G01X402617Y160570D02*
X401541D01*
G01X402539Y158915D02*
X402109Y159345D01*
G01X403764Y159423D02*
X402617Y160570D01*
G01X367282Y630240D02*
Y627335D01*
G01X368507Y629732D02*
Y627780D01*
G01X370482Y633440D02*
X367282Y630240D01*
G01X370990Y632215D02*
X368507Y629732D01*
G01X379175Y633440D02*
X370482D01*
G01X379683Y632215D02*
X370990D01*
G01X381720Y635985D02*
X379175Y633440D01*
G01X382945Y635477D02*
X379683Y632215D01*
G01X381720Y636828D02*
Y635985D01*
G01X382945Y636892D02*
Y635477D01*
G01X368507Y629732D02*
Y627780D01*
G01X367282Y630240D02*
Y627335D01*
G01X370990Y632215D02*
X368507Y629732D01*
G01X370482Y633440D02*
X367282Y630240D01*
G01X379683Y632215D02*
X370990D01*
G01X379175Y633440D02*
X370482D01*
G01X382945Y635477D02*
X379683Y632215D01*
G01X381720Y635985D02*
X379175Y633440D01*
G01X382945Y636892D02*
Y635477D01*
G01X381720Y636828D02*
Y635985D01*
G01X348606Y620068D02*
X350519D01*
G01X348098Y618843D02*
X350565D01*
G01X342561Y626113D02*
X348606Y620068D01*
G01X341336Y625605D02*
X348098Y618843D01*
G01X342561Y630181D02*
Y626113D01*
G01X341336Y630181D02*
Y625605D01*
G01X367282Y630240D02*
Y627335D01*
G01X368507Y629732D02*
Y627780D01*
G01X370482Y633440D02*
X367282Y630240D01*
G01X370990Y632215D02*
X368507Y629732D01*
G01X379175Y633440D02*
X370482D01*
G01X379683Y632215D02*
X370990D01*
G01X381720Y635985D02*
X379175Y633440D01*
G01X382945Y635477D02*
X379683Y632215D01*
G01X381720Y636828D02*
Y635985D01*
G01X382945Y636892D02*
Y635477D01*
G01X368507Y629732D02*
Y627780D01*
G01X367282Y630240D02*
Y627335D01*
G01X370990Y632215D02*
X368507Y629732D01*
G01X370482Y633440D02*
X367282Y630240D01*
G01X379683Y632215D02*
X370990D01*
G01X379175Y633440D02*
X370482D01*
G01X382945Y635477D02*
X379683Y632215D01*
G01X381720Y635985D02*
X379175Y633440D01*
G01X382945Y636892D02*
Y635477D01*
G01X381720Y636828D02*
Y635985D01*
G01X348098Y618843D02*
X350565D01*
G01X348606Y620068D02*
X350519D01*
G01X341336Y625605D02*
X348098Y618843D01*
G01X342561Y626113D02*
X348606Y620068D01*
G01X341336Y630181D02*
Y625605D01*
G01X342561Y630181D02*
Y626113D01*
G01X348606Y620068D02*
X350519D01*
G01X348098Y618843D02*
X350565D01*
G01X342561Y626113D02*
X348606Y620068D01*
G01X341336Y625605D02*
X348098Y618843D01*
G01X342561Y630181D02*
Y626113D01*
G01X341336Y630181D02*
Y625605D01*
G01X346756Y609055D02*
X343588Y605887D01*
G01X346248Y610280D02*
X343080Y607112D01*
G01X350169Y609055D02*
X346756D01*
G01X350169Y610280D02*
X346248D01*
G01D02*
X343080Y607112D01*
G01X346756Y609055D02*
X343588Y605887D01*
G01X350169Y610280D02*
X346248D01*
G01X350169Y609055D02*
X346756D01*
G01X347720Y615013D02*
X350316D01*
G01X347212Y616238D02*
X350181D01*
G01X347128Y614421D02*
X347720Y615013D01*
G01X346620Y615646D02*
X347212Y616238D01*
G01X340987Y614421D02*
X347128D01*
G01X340987Y615646D02*
X346620D01*
G01X347212Y616238D02*
X350181D01*
G01X347720Y615013D02*
X350316D01*
G01X346620Y615646D02*
X347212Y616238D01*
G01X347128Y614421D02*
X347720Y615013D01*
G01X340987Y615646D02*
X346620D01*
G01X340987Y614421D02*
X347128D01*
G01X348098Y618843D02*
X350565D01*
G01X348606Y620068D02*
X350519D01*
G01X341336Y625605D02*
X348098Y618843D01*
G01X342561Y626113D02*
X348606Y620068D01*
G01X341336Y630181D02*
Y625605D01*
G01X342561Y630181D02*
Y626113D01*
G01X346756Y609055D02*
X343588Y605887D01*
G01X346248Y610280D02*
X343080Y607112D01*
G01X350169Y609055D02*
X346756D01*
G01X350169Y610280D02*
X346248D01*
G01D02*
X343080Y607112D01*
G01X346756Y609055D02*
X343588Y605887D01*
G01X350169Y610280D02*
X346248D01*
G01X350169Y609055D02*
X346756D01*
G01X347720Y615013D02*
X350316D01*
G01X347212Y616238D02*
X350181D01*
G01X347128Y614421D02*
X347720Y615013D01*
G01X346620Y615646D02*
X347212Y616238D01*
G01X340987Y614421D02*
X347128D01*
G01X340987Y615646D02*
X346620D01*
G01X347212Y616238D02*
X350181D01*
G01X347720Y615013D02*
X350316D01*
G01X346620Y615646D02*
X347212Y616238D01*
G01X347128Y614421D02*
X347720Y615013D01*
G01X340987Y615646D02*
X346620D01*
G01X340987Y614421D02*
X347128D01*
G01X424472Y99548D02*
X412177D01*
G01X423964Y98323D02*
X411669D01*
G01X436359Y87661D02*
X424472Y99548D01*
G01X435851Y86436D02*
X423964Y98323D01*
G01X448726Y87661D02*
X436359D01*
G01X449234Y86436D02*
X435851D01*
G01X452703Y91638D02*
X448726Y87661D01*
G01X453928Y91130D02*
X449234Y86436D01*
G01X452703Y174665D02*
Y91638D01*
G01X453928Y175173D02*
Y91130D01*
G01X423964Y98323D02*
X411669D01*
G01X424472Y99548D02*
X412177D01*
G01X435851Y86436D02*
X423964Y98323D01*
G01X436359Y87661D02*
X424472Y99548D01*
G01X449234Y86436D02*
X435851D01*
G01X448726Y87661D02*
X436359D01*
G01X453928Y91130D02*
X449234Y86436D01*
G01X452703Y91638D02*
X448726Y87661D01*
G01X453928Y175173D02*
Y91130D01*
G01X452703Y174665D02*
Y91638D01*
G01X424472Y99548D02*
X412177D01*
G01X423964Y98323D02*
X411669D01*
G01X436359Y87661D02*
X424472Y99548D01*
G01X435851Y86436D02*
X423964Y98323D01*
G01X448726Y87661D02*
X436359D01*
G01X449234Y86436D02*
X435851D01*
G01X452703Y91638D02*
X448726Y87661D01*
G01X453928Y91130D02*
X449234Y86436D01*
G01X452703Y174665D02*
Y91638D01*
G01X453928Y175173D02*
Y91130D01*
G01X423964Y98323D02*
X411669D01*
G01X424472Y99548D02*
X412177D01*
G01X435851Y86436D02*
X423964Y98323D01*
G01X436359Y87661D02*
X424472Y99548D01*
G01X449234Y86436D02*
X435851D01*
G01X448726Y87661D02*
X436359D01*
G01X453928Y91130D02*
X449234Y86436D01*
G01X452703Y91638D02*
X448726Y87661D01*
G01X453928Y175173D02*
Y91130D01*
G01X452703Y174665D02*
Y91638D01*
G01X452025Y175343D02*
X452703Y174665D01*
G01X452533Y176568D02*
X453928Y175173D01*
G01X450520Y175343D02*
X452025D01*
G01X450478Y176568D02*
X452533D01*
G01D02*
X453928Y175173D01*
G01X452025Y175343D02*
X452703Y174665D01*
G01X450478Y176568D02*
X452533D01*
G01X450520Y175343D02*
X452025D01*
G01D02*
X452703Y174665D01*
G01X452533Y176568D02*
X453928Y175173D01*
G01X450520Y175343D02*
X452025D01*
G01X450478Y176568D02*
X452533D01*
G01D02*
X453928Y175173D01*
G01X452025Y175343D02*
X452703Y174665D01*
G01X450478Y176568D02*
X452533D01*
G01X450520Y175343D02*
X452025D01*
G01X523159Y105475D02*
X520607D01*
G01X522651Y106700D02*
X520900D01*
G01X525079Y107395D02*
X523159Y105475D01*
G01X523854Y107903D02*
X522651Y106700D01*
G01X525079Y170152D02*
Y107395D01*
G01X523854Y170660D02*
Y107903D01*
G01X522651Y106700D02*
X520900D01*
G01X523159Y105475D02*
X520607D01*
G01X523854Y107903D02*
X522651Y106700D01*
G01X525079Y107395D02*
X523159Y105475D01*
G01X523854Y170660D02*
Y107903D01*
G01X525079Y170152D02*
Y107395D01*
G01X525563Y170636D02*
X525079Y170152D01*
G01X525055Y171861D02*
X523854Y170660D01*
G01X526764Y170636D02*
X525563D01*
G01X525055Y171861D02*
X523854Y170660D01*
G01X526761Y171861D02*
X525055D01*
G01D02*
X523854Y170660D01*
G01X525563Y170636D02*
X525079Y170152D01*
G01X526764Y170636D02*
X525563D01*
G01X526761Y171861D02*
X525055D01*
G01X526764Y170636D02*
X525563D01*
G01X794326Y305766D02*
Y302917D01*
G01X793101Y306274D02*
Y302943D01*
G01X802742Y314182D02*
X794326Y305766D01*
G01X802234Y315407D02*
X793101Y306274D01*
G01D02*
Y302943D01*
G01X794326Y305766D02*
Y302917D01*
G01X802234Y315407D02*
X793101Y306274D01*
G01X802742Y314182D02*
X794326Y305766D01*
G01D02*
Y302917D01*
G01X793101Y306274D02*
Y302943D01*
G01X802742Y314182D02*
X794326Y305766D01*
G01X802234Y315407D02*
X793101Y306274D01*
G01D02*
Y302943D01*
G01X794326Y305766D02*
Y302917D01*
G01X802234Y315407D02*
X793101Y306274D01*
G01X802742Y314182D02*
X794326Y305766D01*
G01X782535Y306400D02*
Y302110D01*
G01X781310Y306908D02*
Y302564D01*
G01X789104Y312969D02*
X782535Y306400D01*
G01X787879Y313477D02*
X781310Y306908D01*
G01X789104Y332538D02*
Y312969D01*
G01X787879Y333047D02*
Y313477D01*
G01X781310Y306908D02*
Y302564D01*
G01X782535Y306400D02*
Y302110D01*
G01X787879Y313477D02*
X781310Y306908D01*
G01X789104Y312969D02*
X782535Y306400D01*
G01X787879Y333047D02*
Y313477D01*
G01X789104Y332538D02*
Y312969D01*
G01X785827Y304607D02*
Y301968D01*
G01X784602Y305115D02*
Y302680D01*
G01X800225Y319005D02*
X785827Y304607D01*
G01X799000Y319513D02*
X784602Y305115D01*
G01X799000Y331668D02*
Y319513D01*
G01X784602Y305115D02*
Y302680D01*
G01X785827Y304607D02*
Y301968D01*
G01X799000Y319513D02*
X784602Y305115D01*
G01X800225Y319005D02*
X785827Y304607D01*
G01X799000Y331668D02*
Y319513D01*
G01X753894Y311158D02*
Y302405D01*
G01X752669Y300350D02*
Y310650D01*
G01X751900Y313152D02*
X753894Y311158D01*
G01X752669Y310650D02*
X750675Y312644D01*
G01X751900Y322500D02*
Y313152D01*
G01X750675Y312644D02*
Y321992D01*
G01X746200Y328200D02*
X751900Y322500D01*
G01X750675Y321992D02*
X744975Y327692D01*
G01X746200Y329334D02*
Y328200D01*
G01X744975Y327692D02*
Y329842D01*
G01X747333Y330467D02*
X746200Y329334D01*
G01X744975Y329842D02*
X746466Y331333D01*
G01X744975Y329842D02*
X746466Y331333D01*
G01X747333Y330467D02*
X746200Y329334D01*
G01X744975Y327692D02*
Y329842D01*
G01X746200Y329334D02*
Y328200D01*
G01X750675Y321992D02*
X744975Y327692D01*
G01X746200Y328200D02*
X751900Y322500D01*
G01X750675Y312644D02*
Y321992D01*
G01X751900Y322500D02*
Y313152D01*
G01X752669Y310650D02*
X750675Y312644D01*
G01X751900Y313152D02*
X753894Y311158D01*
G01X752669Y300350D02*
Y310650D01*
G01X753894Y311158D02*
Y302405D01*
G01X757272Y330207D02*
Y302176D01*
G01X756047Y299900D02*
Y329699D01*
G01X751200Y336279D02*
X757272Y330207D01*
G01X756047Y329699D02*
X749975Y335771D01*
G01X756047Y329699D02*
X749975Y335771D01*
G01X751200Y336279D02*
X757272Y330207D01*
G01X756047Y299900D02*
Y329699D01*
G01X757272Y330207D02*
Y302176D01*
G01X763277Y310717D02*
Y302470D01*
G01X762052Y300298D02*
Y310209D01*
G01X762000Y311994D02*
X763277Y310717D01*
G01X762052Y310209D02*
X760775Y311486D01*
G01X762000Y326534D02*
Y311994D01*
G01X760775Y311486D02*
Y327043D01*
G01X764833Y329367D02*
X762000Y326534D01*
G01X760943Y327210D02*
X763966Y330233D01*
G01X760943Y327210D02*
X763966Y330233D01*
G01X764833Y329367D02*
X762000Y326534D01*
G01X760775Y311486D02*
Y327043D01*
G01X762000Y326534D02*
Y311994D01*
G01X762052Y310209D02*
X760775Y311486D01*
G01X762000Y311994D02*
X763277Y310717D01*
G01X762052Y300298D02*
Y310209D01*
G01X763277Y310717D02*
Y302470D01*
G01X766549Y313396D02*
Y302348D01*
G01X765324Y300276D02*
Y313904D01*
G01X772525Y319372D02*
X766549Y313396D01*
G01X765324Y313904D02*
X771300Y319880D01*
G01X772525Y329975D02*
Y319372D01*
G01X771300Y319880D02*
Y329467D01*
G01X761300Y341200D02*
X772525Y329975D01*
G01X771300Y329467D02*
X760075Y340692D01*
G01X771300Y329467D02*
X760075Y340692D01*
G01X761300Y341200D02*
X772525Y329975D01*
G01X771300Y319880D02*
Y329467D01*
G01X772525Y329975D02*
Y319372D01*
G01X765324Y313904D02*
X771300Y319880D01*
G01X772525Y319372D02*
X766549Y313396D01*
G01X765324Y300276D02*
Y313904D01*
G01X766549Y313396D02*
Y302348D01*
G01X772952Y312799D02*
Y302244D01*
G01X771727Y313307D02*
Y300000D01*
G01X777576Y317423D02*
X772952Y312799D01*
G01X776351Y317931D02*
X771727Y313307D01*
G01X777576Y331425D02*
Y317423D01*
G01X776351Y330917D02*
Y317931D01*
G01X771727Y313307D02*
Y300000D01*
G01X772952Y312799D02*
Y302244D01*
G01X776351Y317931D02*
X771727Y313307D01*
G01X777576Y317423D02*
X772952Y312799D01*
G01X776351Y330917D02*
Y317931D01*
G01X777576Y331425D02*
Y317423D01*
G01X776102Y308984D02*
Y302244D01*
G01X774877Y300000D02*
Y309492D01*
G01X784101Y316983D02*
X776102Y308984D01*
G01X774877Y309492D02*
X782876Y317491D01*
G01X784101Y336306D02*
Y316983D01*
G01X782876Y317491D02*
Y335798D01*
G01Y317491D02*
Y335798D01*
G01X784101Y336306D02*
Y316983D01*
G01X774877Y309492D02*
X782876Y317491D01*
G01X784101Y316983D02*
X776102Y308984D01*
G01X774877Y300000D02*
Y309492D01*
G01X776102Y308984D02*
Y302244D01*
G01X793029Y336463D02*
X789104Y332538D01*
G01X792163Y337330D02*
X788047Y333214D01*
G01X792163Y337330D02*
X788047Y333214D01*
G01X793029Y336463D02*
X789104Y332538D01*
G01X801165Y333835D02*
X799000Y331668D01*
G01X801165Y333835D02*
X799000Y331668D01*
G01X751200Y339234D02*
Y336279D01*
G01X749975Y335771D02*
Y339742D01*
G01X753229Y341263D02*
X751200Y339234D01*
G01X749975Y339742D02*
X752363Y342130D01*
G01X749975Y339742D02*
X752363Y342130D01*
G01X753229Y341263D02*
X751200Y339234D01*
G01X749975Y335771D02*
Y339742D01*
G01X751200Y339234D02*
Y336279D01*
G01X761300Y345316D02*
Y341200D01*
G01X760075Y340692D02*
Y345824D01*
G01X763947Y347963D02*
X761300Y345316D01*
G01X760075Y345824D02*
X763081Y348830D01*
G01X760075Y345824D02*
X763081Y348830D01*
G01X763947Y347963D02*
X761300Y345316D01*
G01X760075Y340692D02*
Y345824D01*
G01X761300Y345316D02*
Y341200D01*
G01X775000Y334000D02*
X777576Y331425D01*
G01X775692Y331575D02*
X776351Y330917D01*
G01X773775Y333492D02*
X775692Y331575D01*
G01X775000Y334916D02*
Y334000D01*
G01X773775Y335424D02*
Y333492D01*
G01X776047Y335963D02*
X775000Y334916D01*
G01X775181Y336830D02*
X773775Y335424D01*
G01X775692Y331575D02*
X776351Y330917D01*
G01X775000Y334000D02*
X777576Y331425D01*
G01X773775Y333492D02*
X775692Y331575D01*
G01X775000Y334000D02*
X777576Y331425D01*
G01X773775Y335424D02*
Y333492D01*
G01X775000Y334916D02*
Y334000D01*
G01X775181Y336830D02*
X773775Y335424D01*
G01X776047Y335963D02*
X775000Y334916D01*
G01X778600Y341807D02*
X784101Y336306D01*
G01X782876Y335798D02*
X777375Y341299D01*
G01X778600Y345734D02*
Y341807D01*
G01X777375Y341299D02*
Y346242D01*
G01X781133Y348267D02*
X778600Y345734D01*
G01X777375Y346242D02*
X780266Y349133D01*
G01X777375Y346242D02*
X780266Y349133D01*
G01X781133Y348267D02*
X778600Y345734D01*
G01X777375Y341299D02*
Y346242D01*
G01X778600Y345734D02*
Y341807D01*
G01X782876Y335798D02*
X777375Y341299D01*
G01X778600Y341807D02*
X784101Y336306D01*
G01X813984Y314182D02*
X802742D01*
G01X813476Y315407D02*
X802234D01*
G01X818300Y318498D02*
X813984Y314182D01*
G01X817075Y319006D02*
X813476Y315407D01*
G01X818300Y321050D02*
Y318498D01*
G01X817075Y320675D02*
Y319006D01*
G01X817991Y327802D02*
Y324258D01*
G01X816766Y328310D02*
Y324016D01*
G01X820074Y329886D02*
X817991Y327802D01*
G01X819207Y330753D02*
X816766Y328310D01*
G01X821210Y331022D02*
X820074Y329886D01*
G01X813476Y315407D02*
X802234D01*
G01X813984Y314182D02*
X802742D01*
G01X817075Y319006D02*
X813476Y315407D01*
G01X818300Y318498D02*
X813984Y314182D01*
G01X817075Y320675D02*
Y319006D01*
G01X818300Y321050D02*
Y318498D01*
G01X816766Y328310D02*
Y324016D01*
G01X817991Y327802D02*
Y324258D01*
G01X819207Y330753D02*
X816766Y328310D01*
G01X820074Y329886D02*
X817991Y327802D01*
G01X821210Y331022D02*
X820074Y329886D01*
G01X813984Y314182D02*
X802742D01*
G01X813476Y315407D02*
X802234D01*
G01X818300Y318498D02*
X813984Y314182D01*
G01X817075Y319006D02*
X813476Y315407D01*
G01X818300Y321050D02*
Y318498D01*
G01X817075Y320675D02*
Y319006D01*
G01X817991Y327802D02*
Y324258D01*
G01X816766Y328310D02*
Y324016D01*
G01X820074Y329886D02*
X817991Y327802D01*
G01X819207Y330753D02*
X816766Y328310D01*
G01X821210Y331022D02*
X820074Y329886D01*
G01X813476Y315407D02*
X802234D01*
G01X813984Y314182D02*
X802742D01*
G01X817075Y319006D02*
X813476Y315407D01*
G01X818300Y318498D02*
X813984Y314182D01*
G01X817075Y320675D02*
Y319006D01*
G01X818300Y321050D02*
Y318498D01*
G01X816766Y328310D02*
Y324016D01*
G01X817991Y327802D02*
Y324258D01*
G01X819207Y330753D02*
X816766Y328310D01*
G01X820074Y329886D02*
X817991Y327802D01*
G01X821210Y331022D02*
X820074Y329886D01*
G01X800225Y331160D02*
Y319005D01*
G01Y331160D02*
Y319005D01*
G01X820343Y331889D02*
X819207Y330753D01*
G01X820343Y331889D02*
X819207Y330753D01*
G01X820343Y331889D02*
X819207Y330753D01*
G01X820343Y331889D02*
X819207Y330753D01*
G01X802432Y333368D02*
X800225Y331160D01*
G01X802465Y335135D02*
X801165Y333835D01*
G01X803332Y334268D02*
X802432Y333368D01*
G01X802465Y335135D02*
X801165Y333835D01*
G01X802432Y333368D02*
X800225Y331160D01*
G01X802465Y335135D02*
X801165Y333835D01*
G01X802432Y333368D02*
X800225Y331160D01*
G01X803332Y334268D02*
X802432Y333368D01*
M02*
